FILE_TYPE = MACRO_DRAWING;
SET COLOR_WIRE YELLOW;
SET COLOR_PROP ORANGE;
SET COLOR_DOT WHITE;
SET COLOR_ARC YELLOW;
SET COLOR_BODY GREEN;
SET COLOR_NOTE PURPLE;
SET PROP_DISPLAY VALUE;
SET PAGE_NUMBER P422;
FORCEADD Q_CAP..1
(-6350 3375);
FORCEPROP 1 LAST LOCATION C775
J 0
(-6300 3475);
DISPLAY 0.978723 (-6300 3475);
PAINT WHITE (-6300 3475);
FORCEPROP 0 LAST $SEC 1
J 0
(-6300 3525);
DISPLAY 0.680851 (-6300 3525);
PAINT MONO (-6300 3525);
DISPLAY INVISIBLE (-6300 3525);
FORCEPROP 0 LAST CDS_SEC 1
J 0
(-6300 3525);
DISPLAY 0.680851 (-6300 3525);
DISPLAY INVISIBLE (-6300 3525);
FORCEPROP 1 LASTPIN (-6350 3475) $PN 1
J 0
(-6340 3455);
DISPLAY 0.787234 (-6340 3455);
PAINT MONO (-6340 3455);
FORCEPROP 1 LASTPIN (-6350 3275) $PN 2
J 0
(-6340 3255);
DISPLAY 0.787234 (-6340 3255);
PAINT MONO (-6340 3255);
FORCEPROP 1 LAST VOLTAGE 10V
J 0
(-6300 3375);
DISPLAY 0.638298 (-6300 3375);
FORCEPROP 1 LAST PACK_TYPE C0201
J 0
(-6300 3225);
DISPLAY 0.638298 (-6300 3225);
FORCEPROP 1 LAST MATERIAL X7S
J 0
(-6300 3275);
DISPLAY 0.638298 (-6300 3275);
FORCEPROP 1 LAST VALUE 0.1UF
J 0
(-6300 3425);
DISPLAY 0.638298 (-6300 3425);
FORCEPROP 1 LAST TOLERANCE 10%
J 0
(-6300 3325);
DISPLAY 0.638298 (-6300 3325);
FORCEPROP 2 LAST CDS_LIB pure_quanta
J 0
(-6350 3375);
DISPLAY INVISIBLE (-6350 3375);
FORCEPROP 1 LAST PATH I10
J 0
(-6300 3525);
DISPLAY 0.978723 (-6300 3525);
PAINT WHITE (-6300 3525);
DISPLAY INVISIBLE (-6300 3525);
FORCEPROP 1 LAST PART_NUMBER CH4102K6E00
J 0
(-6300 3225);
DISPLAY 0.978723 (-6300 3225);
DISPLAY INVISIBLE (-6300 3225);
FORCEADD P1V0..1
(-6750 3775);
FORCEPROP 3 LASTPIN (-6750 3725) SIG_NAME P1V8_CPU0_RT2_1A_1D\g
J 0
(-6740 3735);
DISPLAY 0.659574 (-6740 3735);
PAINT MONO (-6740 3735);
DISPLAY INVISIBLE (-6740 3735);
FORCEPROP 1 LAST HDL_POWER P1V8_CPU0_RT2_1A_1D
J 1
(-6750 3825);
DISPLAY 0.489362 (-6750 3825);
PAINT SKYBLUE (-6750 3825);
FORCEPROP 2 LAST CDS_LIB pure_quanta_power
J 0
(-6750 3775);
DISPLAY INVISIBLE (-6750 3775);
FORCEPROP 1 LAST PATH I11
J 0
(-6700 3800);
DISPLAY 0.872340 (-6700 3800);
PAINT AQUA (-6700 3800);
DISPLAY INVISIBLE (-6700 3800);
FORCEADD Q_CAP..1
(-6625 4475);
FORCEPROP 1 LAST LOCATION C671
J 0
(-6575 4575);
DISPLAY 0.808511 (-6575 4575);
PAINT WHITE (-6575 4575);
FORCEPROP 0 LAST $SEC 1
J 0
(-6575 4625);
DISPLAY 0.680851 (-6575 4625);
PAINT MONO (-6575 4625);
DISPLAY INVISIBLE (-6575 4625);
FORCEPROP 0 LAST CDS_SEC 1
J 0
(-6575 4625);
DISPLAY 0.680851 (-6575 4625);
DISPLAY INVISIBLE (-6575 4625);
FORCEPROP 1 LASTPIN (-6625 4575) $PN 1
J 0
(-6615 4555);
DISPLAY 0.787234 (-6615 4555);
PAINT MONO (-6615 4555);
FORCEPROP 1 LASTPIN (-6625 4375) $PN 2
J 0
(-6615 4355);
DISPLAY 0.787234 (-6615 4355);
PAINT MONO (-6615 4355);
FORCEPROP 1 LAST VOLTAGE 6.3V
J 0
(-6575 4475);
DISPLAY 0.510638 (-6575 4475);
FORCEPROP 1 LAST TOLERANCE 20%
J 0
(-6575 4425);
DISPLAY 0.510638 (-6575 4425);
FORCEPROP 1 LAST MATERIAL X6S
J 0
(-6575 4375);
DISPLAY 0.510638 (-6575 4375);
FORCEPROP 1 LAST PACK_TYPE C0402
J 0
(-6575 4325);
DISPLAY 0.510638 (-6575 4325);
FORCEPROP 1 LAST VALUE 10UF
J 0
(-6575 4525);
DISPLAY 0.510638 (-6575 4525);
FORCEPROP 2 LAST CDS_LIB pure_quanta
J 0
(-6625 4475);
DISPLAY INVISIBLE (-6625 4475);
FORCEPROP 1 LAST PATH I12
J 0
(-6575 4625);
DISPLAY 0.978723 (-6575 4625);
PAINT WHITE (-6575 4625);
DISPLAY INVISIBLE (-6575 4625);
FORCEPROP 1 LAST PART_NUMBER CH6101MEB01
J 0
(-6575 4325);
DISPLAY 0.978723 (-6575 4325);
DISPLAY INVISIBLE (-6575 4325);
FORCEADD Q_CAP..1
(-6425 4475);
FORCEPROP 1 LAST LOCATION C670
J 0
(-6375 4575);
DISPLAY 0.638298 (-6375 4575);
PAINT WHITE (-6375 4575);
FORCEPROP 0 LAST $SEC 1
J 0
(-6375 4600);
DISPLAY 0.680851 (-6375 4600);
PAINT MONO (-6375 4600);
DISPLAY INVISIBLE (-6375 4600);
FORCEPROP 0 LAST CDS_SEC 1
J 0
(-6375 4600);
DISPLAY 0.680851 (-6375 4600);
DISPLAY INVISIBLE (-6375 4600);
FORCEPROP 1 LASTPIN (-6425 4575) $PN 1
J 0
(-6415 4555);
DISPLAY 0.787234 (-6415 4555);
PAINT MONO (-6415 4555);
FORCEPROP 1 LASTPIN (-6425 4375) $PN 2
J 0
(-6415 4355);
DISPLAY 0.787234 (-6415 4355);
PAINT MONO (-6415 4355);
FORCEPROP 1 LAST VOLTAGE 6.3V
J 0
(-6375 4475);
DISPLAY 0.510638 (-6375 4475);
FORCEPROP 1 LAST TOLERANCE 20%
J 0
(-6375 4425);
DISPLAY 0.510638 (-6375 4425);
FORCEPROP 1 LAST PACK_TYPE 0402
J 0
(-6375 4325);
DISPLAY 0.510638 (-6375 4325);
FORCEPROP 1 LAST MATERIAL X6S
J 0
(-6375 4375);
DISPLAY 0.510638 (-6375 4375);
FORCEPROP 1 LAST VALUE 4.7UF
J 0
(-6375 4525);
DISPLAY 0.510638 (-6375 4525);
FORCEPROP 2 LAST CDS_LIB pure_quanta
J 0
(-6425 4475);
DISPLAY INVISIBLE (-6425 4475);
FORCEPROP 1 LAST PATH I13
J 0
(-6375 4625);
DISPLAY 0.978723 (-6375 4625);
PAINT WHITE (-6375 4625);
DISPLAY INVISIBLE (-6375 4625);
FORCEPROP 1 LAST PART_NUMBER CH5471MEB01
J 0
(-6375 4325);
DISPLAY 0.978723 (-6375 4325);
DISPLAY INVISIBLE (-6375 4325);
FORCEADD UNIVERSAL_GND..1
(-6000 4150);
FORCEPROP 3 LASTPIN (-6000 4200) SIG_NAME GND\g
J 0
(-5990 4210);
DISPLAY 0.659574 (-5990 4210);
PAINT MONO (-5990 4210);
DISPLAY INVISIBLE (-5990 4210);
FORCEPROP 2 LAST CDS_LIB pure_quanta_power
J 0
(-6000 4150);
DISPLAY INVISIBLE (-6000 4150);
FORCEPROP 1 LAST HDL_POWER GND
J 1
(-5975 4075);
DISPLAY 0.872340 (-5975 4075);
PAINT GREEN (-5975 4075);
DISPLAY INVISIBLE (-5975 4075);
FORCEPROP 1 LAST PATH I14
J 0
(-5925 4150);
DISPLAY 0.872340 (-5925 4150);
PAINT AQUA (-5925 4150);
DISPLAY INVISIBLE (-5925 4150);
FORCEADD Q_CAP..1
(-6200 4475);
FORCEPROP 1 LAST LOCATION C673
J 0
(-6150 4575);
DISPLAY 0.808511 (-6150 4575);
PAINT WHITE (-6150 4575);
FORCEPROP 0 LAST $SEC 1
J 0
(-6150 4625);
DISPLAY 0.680851 (-6150 4625);
PAINT MONO (-6150 4625);
DISPLAY INVISIBLE (-6150 4625);
FORCEPROP 0 LAST CDS_SEC 1
J 0
(-6150 4625);
DISPLAY 0.680851 (-6150 4625);
DISPLAY INVISIBLE (-6150 4625);
FORCEPROP 1 LASTPIN (-6200 4575) $PN 1
J 0
(-6190 4555);
DISPLAY 0.787234 (-6190 4555);
PAINT MONO (-6190 4555);
FORCEPROP 1 LASTPIN (-6200 4375) $PN 2
J 0
(-6190 4355);
DISPLAY 0.787234 (-6190 4355);
PAINT MONO (-6190 4355);
FORCEPROP 1 LAST PACK_TYPE 0201
J 0
(-6150 4325);
DISPLAY 0.510638 (-6150 4325);
FORCEPROP 1 LAST MATERIAL X6S
J 0
(-6150 4375);
DISPLAY 0.510638 (-6150 4375);
FORCEPROP 1 LAST VOLTAGE 4V
J 0
(-6150 4475);
DISPLAY 0.510638 (-6150 4475);
FORCEPROP 1 LAST TOLERANCE 20%
J 0
(-6150 4425);
DISPLAY 0.510638 (-6150 4425);
FORCEPROP 1 LAST VALUE 1UF
J 0
(-6150 4525);
DISPLAY 0.510638 (-6150 4525);
FORCEPROP 2 LAST CDS_LIB pure_quanta
J 0
(-6200 4475);
DISPLAY INVISIBLE (-6200 4475);
FORCEPROP 1 LAST PATH I15
J 0
(-6150 4625);
DISPLAY 0.978723 (-6150 4625);
PAINT WHITE (-6150 4625);
DISPLAY INVISIBLE (-6150 4625);
FORCEPROP 1 LAST PART_NUMBER CH-10KMEE00
J 0
(-6150 4325);
DISPLAY 0.510638 (-6150 4325);
DISPLAY INVISIBLE (-6150 4325);
FORCEADD Q_CAP..1
(-6000 4475);
FORCEPROP 1 LAST LOCATION C677
J 0
(-5950 4575);
DISPLAY 0.808511 (-5950 4575);
PAINT WHITE (-5950 4575);
FORCEPROP 0 LAST $SEC 1
J 0
(-5950 4625);
DISPLAY 0.680851 (-5950 4625);
PAINT MONO (-5950 4625);
DISPLAY INVISIBLE (-5950 4625);
FORCEPROP 0 LAST CDS_SEC 1
J 0
(-5950 4625);
DISPLAY 0.680851 (-5950 4625);
DISPLAY INVISIBLE (-5950 4625);
FORCEPROP 1 LASTPIN (-6000 4575) $PN 1
J 0
(-5990 4555);
DISPLAY 0.787234 (-5990 4555);
PAINT MONO (-5990 4555);
FORCEPROP 1 LASTPIN (-6000 4375) $PN 2
J 0
(-5990 4355);
DISPLAY 0.787234 (-5990 4355);
PAINT MONO (-5990 4355);
FORCEPROP 1 LAST VALUE 1UF
J 0
(-5950 4525);
DISPLAY 0.510638 (-5950 4525);
FORCEPROP 1 LAST TOLERANCE 20%
J 0
(-5950 4425);
DISPLAY 0.510638 (-5950 4425);
FORCEPROP 1 LAST VOLTAGE 4V
J 0
(-5950 4475);
DISPLAY 0.510638 (-5950 4475);
FORCEPROP 1 LAST MATERIAL X6S
J 0
(-5950 4375);
DISPLAY 0.510638 (-5950 4375);
FORCEPROP 1 LAST PACK_TYPE 0201
J 0
(-5950 4325);
DISPLAY 0.510638 (-5950 4325);
FORCEPROP 2 LAST CDS_LIB pure_quanta
J 0
(-6000 4475);
DISPLAY INVISIBLE (-6000 4475);
FORCEPROP 1 LAST PATH I16
J 0
(-5950 4625);
DISPLAY 0.978723 (-5950 4625);
PAINT WHITE (-5950 4625);
DISPLAY INVISIBLE (-5950 4625);
FORCEPROP 1 LAST PART_NUMBER CH-10KMEE00
J 0
(-5950 4325);
DISPLAY 0.510638 (-5950 4325);
DISPLAY INVISIBLE (-5950 4325);
FORCEADD Q_CAP..1
(-5775 4475);
FORCEPROP 1 LAST LOCATION C774
J 0
(-5725 4575);
DISPLAY 0.978723 (-5725 4575);
PAINT WHITE (-5725 4575);
FORCEPROP 0 LAST $SEC 1
J 0
(-5725 4625);
DISPLAY 0.680851 (-5725 4625);
PAINT MONO (-5725 4625);
DISPLAY INVISIBLE (-5725 4625);
FORCEPROP 0 LAST CDS_SEC 1
J 0
(-5725 4625);
DISPLAY 0.680851 (-5725 4625);
DISPLAY INVISIBLE (-5725 4625);
FORCEPROP 1 LASTPIN (-5775 4575) $PN 1
J 0
(-5765 4555);
DISPLAY 0.787234 (-5765 4555);
PAINT MONO (-5765 4555);
FORCEPROP 1 LASTPIN (-5775 4375) $PN 2
J 0
(-5765 4355);
DISPLAY 0.787234 (-5765 4355);
PAINT MONO (-5765 4355);
FORCEPROP 1 LAST TOLERANCE 10%
J 0
(-5725 4425);
DISPLAY 0.638298 (-5725 4425);
FORCEPROP 1 LAST VALUE 0.1UF
J 0
(-5725 4525);
DISPLAY 0.638298 (-5725 4525);
FORCEPROP 1 LAST VOLTAGE 10V
J 0
(-5725 4475);
DISPLAY 0.638298 (-5725 4475);
FORCEPROP 1 LAST MATERIAL X7S
J 0
(-5725 4375);
DISPLAY 0.638298 (-5725 4375);
FORCEPROP 1 LAST PACK_TYPE C0201
J 0
(-5725 4325);
DISPLAY 0.638298 (-5725 4325);
FORCEPROP 2 LAST CDS_LIB pure_quanta
J 0
(-5775 4475);
DISPLAY INVISIBLE (-5775 4475);
FORCEPROP 1 LAST PATH I17
J 0
(-5725 4625);
DISPLAY 0.978723 (-5725 4625);
PAINT WHITE (-5725 4625);
DISPLAY INVISIBLE (-5725 4625);
FORCEPROP 1 LAST PART_NUMBER CH4102K6E00
J 0
(-5725 4325);
DISPLAY 0.978723 (-5725 4325);
DISPLAY INVISIBLE (-5725 4325);
FORCEADD Q_CAP..1
(-5525 4475);
FORCEPROP 1 LAST LOCATION C776
J 0
(-5475 4575);
DISPLAY 0.978723 (-5475 4575);
PAINT WHITE (-5475 4575);
FORCEPROP 0 LAST $SEC 1
J 0
(-5475 4625);
DISPLAY 0.680851 (-5475 4625);
PAINT MONO (-5475 4625);
DISPLAY INVISIBLE (-5475 4625);
FORCEPROP 0 LAST CDS_SEC 1
J 0
(-5475 4625);
DISPLAY 0.680851 (-5475 4625);
DISPLAY INVISIBLE (-5475 4625);
FORCEPROP 1 LASTPIN (-5525 4575) $PN 1
J 0
(-5515 4555);
DISPLAY 0.787234 (-5515 4555);
PAINT MONO (-5515 4555);
FORCEPROP 1 LASTPIN (-5525 4375) $PN 2
J 0
(-5515 4355);
DISPLAY 0.787234 (-5515 4355);
PAINT MONO (-5515 4355);
FORCEPROP 1 LAST PACK_TYPE C0201
J 0
(-5475 4325);
DISPLAY 0.638298 (-5475 4325);
FORCEPROP 1 LAST MATERIAL X7S
J 0
(-5475 4375);
DISPLAY 0.638298 (-5475 4375);
FORCEPROP 1 LAST VOLTAGE 10V
J 0
(-5475 4475);
DISPLAY 0.638298 (-5475 4475);
FORCEPROP 1 LAST VALUE 0.1UF
J 0
(-5475 4525);
DISPLAY 0.638298 (-5475 4525);
FORCEPROP 1 LAST TOLERANCE 10%
J 0
(-5475 4425);
DISPLAY 0.638298 (-5475 4425);
FORCEPROP 2 LAST CDS_LIB pure_quanta
J 0
(-5525 4475);
DISPLAY INVISIBLE (-5525 4475);
FORCEPROP 1 LAST PATH I18
J 0
(-5475 4625);
DISPLAY 0.978723 (-5475 4625);
PAINT WHITE (-5475 4625);
DISPLAY INVISIBLE (-5475 4625);
FORCEPROP 1 LAST PART_NUMBER CH4102K6E00
J 0
(-5475 4325);
DISPLAY 0.978723 (-5475 4325);
DISPLAY INVISIBLE (-5475 4325);
FORCEADD Q_CAP..1
(-5275 4475);
FORCEPROP 1 LAST LOCATION C777
J 0
(-5225 4575);
DISPLAY 0.978723 (-5225 4575);
PAINT WHITE (-5225 4575);
FORCEPROP 0 LAST $SEC 1
J 0
(-5225 4625);
DISPLAY 0.680851 (-5225 4625);
PAINT MONO (-5225 4625);
DISPLAY INVISIBLE (-5225 4625);
FORCEPROP 0 LAST CDS_SEC 1
J 0
(-5225 4625);
DISPLAY 0.680851 (-5225 4625);
DISPLAY INVISIBLE (-5225 4625);
FORCEPROP 1 LASTPIN (-5275 4575) $PN 1
J 0
(-5265 4555);
DISPLAY 0.787234 (-5265 4555);
PAINT MONO (-5265 4555);
FORCEPROP 1 LASTPIN (-5275 4375) $PN 2
J 0
(-5265 4355);
DISPLAY 0.787234 (-5265 4355);
PAINT MONO (-5265 4355);
FORCEPROP 1 LAST PACK_TYPE C0201
J 0
(-5225 4325);
DISPLAY 0.638298 (-5225 4325);
FORCEPROP 1 LAST TOLERANCE 10%
J 0
(-5225 4425);
DISPLAY 0.638298 (-5225 4425);
FORCEPROP 1 LAST VALUE 0.1UF
J 0
(-5225 4525);
DISPLAY 0.638298 (-5225 4525);
FORCEPROP 1 LAST VOLTAGE 10V
J 0
(-5225 4475);
DISPLAY 0.638298 (-5225 4475);
FORCEPROP 1 LAST MATERIAL X7S
J 0
(-5225 4375);
DISPLAY 0.638298 (-5225 4375);
FORCEPROP 2 LAST CDS_LIB pure_quanta
J 0
(-5275 4475);
DISPLAY INVISIBLE (-5275 4475);
FORCEPROP 1 LAST PATH I19
J 0
(-5225 4625);
DISPLAY 0.978723 (-5225 4625);
PAINT WHITE (-5225 4625);
DISPLAY INVISIBLE (-5225 4625);
FORCEPROP 1 LAST PART_NUMBER CH4102K6E00
J 0
(-5225 4325);
DISPLAY 0.978723 (-5225 4325);
DISPLAY INVISIBLE (-5225 4325);
FORCEADD Q_CAP..1
(-5000 4475);
FORCEPROP 1 LAST LOCATION C778
J 0
(-4950 4575);
DISPLAY 0.978723 (-4950 4575);
PAINT WHITE (-4950 4575);
FORCEPROP 0 LAST $SEC 1
J 0
(-4950 4625);
DISPLAY 0.680851 (-4950 4625);
PAINT MONO (-4950 4625);
DISPLAY INVISIBLE (-4950 4625);
FORCEPROP 0 LAST CDS_SEC 1
J 0
(-4950 4625);
DISPLAY 0.680851 (-4950 4625);
DISPLAY INVISIBLE (-4950 4625);
FORCEPROP 1 LASTPIN (-5000 4575) $PN 1
J 0
(-4990 4555);
DISPLAY 0.787234 (-4990 4555);
PAINT MONO (-4990 4555);
FORCEPROP 1 LASTPIN (-5000 4375) $PN 2
J 0
(-4990 4355);
DISPLAY 0.787234 (-4990 4355);
PAINT MONO (-4990 4355);
FORCEPROP 1 LAST TOLERANCE 10%
J 0
(-4950 4425);
DISPLAY 0.638298 (-4950 4425);
FORCEPROP 1 LAST VALUE 0.1UF
J 0
(-4950 4525);
DISPLAY 0.638298 (-4950 4525);
FORCEPROP 1 LAST PACK_TYPE C0201
J 0
(-4950 4325);
DISPLAY 0.638298 (-4950 4325);
FORCEPROP 1 LAST MATERIAL X7S
J 0
(-4950 4375);
DISPLAY 0.638298 (-4950 4375);
FORCEPROP 1 LAST VOLTAGE 10V
J 0
(-4950 4475);
DISPLAY 0.638298 (-4950 4475);
FORCEPROP 2 LAST CDS_LIB pure_quanta
J 0
(-5000 4475);
DISPLAY INVISIBLE (-5000 4475);
FORCEPROP 1 LAST PATH I20
J 0
(-4950 4625);
DISPLAY 0.978723 (-4950 4625);
PAINT WHITE (-4950 4625);
DISPLAY INVISIBLE (-4950 4625);
FORCEPROP 1 LAST PART_NUMBER CH4102K6E00
J 0
(-4950 4325);
DISPLAY 0.978723 (-4950 4325);
DISPLAY INVISIBLE (-4950 4325);
FORCEADD Q_RES..2
R 2
(-4150 3050);
FORCEPROP 1 LAST LOCATION R1051
J 2
(-4195 3175);
DISPLAY 0.978723 (-4195 3175);
FORCEPROP 0 LAST $SEC 1
J 0
(-4175 3225);
DISPLAY 0.680851 (-4175 3225);
PAINT MONO (-4175 3225);
DISPLAY INVISIBLE (-4175 3225);
FORCEPROP 0 LAST CDS_SEC 1
J 0
(-4175 3225);
DISPLAY 0.680851 (-4175 3225);
DISPLAY INVISIBLE (-4175 3225);
FORCEPROP 1 LASTPIN (-4150 3150) $PN 1
J 2
(-4155 3112);
DISPLAY 0.787234 (-4155 3112);
PAINT MONO (-4155 3112);
FORCEPROP 1 LASTPIN (-4150 2950) $PN 2
J 2
(-4155 2960);
DISPLAY 0.787234 (-4155 2960);
PAINT MONO (-4155 2960);
FORCEPROP 1 LAST VALUE 0
J 2
(-4195 3125);
DISPLAY 0.978723 (-4195 3125);
FORCEPROP 1 LAST MATERIAL EMPTY
J 2
(-4190 2975);
DISPLAY 0.978723 (-4190 2975);
FORCEPROP 1 LAST WATTAGE 1/4W
J 2
(-4190 3025);
DISPLAY 0.978723 (-4190 3025);
FORCEPROP 1 LAST TOLERANCE 5%
J 2
(-4195 3075);
DISPLAY 0.978723 (-4195 3075);
FORCEPROP 1 LAST PACK_TYPE 0603LF
J 2
(-4190 2875);
DISPLAY 0.978723 (-4190 2875);
FORCEPROP 2 LAST CDS_LIB pure_quanta
J 2
(-4150 3050);
DISPLAY INVISIBLE (-4150 3050);
FORCEPROP 1 LAST PATH I21
J 2
(-4200 3225);
DISPLAY 0.978723 (-4200 3225);
PAINT WHITE (-4200 3225);
DISPLAY INVISIBLE (-4200 3225);
FORCEPROP 1 LAST PART_NUMBER CS00006J900
J 2
(-4190 2925);
DISPLAY 0.978723 (-4190 2925);
DISPLAY INVISIBLE (-4190 2925);
FORCEADD Q_RES..1
(-3775 2775);
FORCEPROP 1 LAST LOCATION R1053
J 0
(-3825 2825);
DISPLAY 0.978723 (-3825 2825);
FORCEPROP 0 LAST $SEC 1
J 0
(-3825 2875);
DISPLAY 0.680851 (-3825 2875);
PAINT MONO (-3825 2875);
DISPLAY INVISIBLE (-3825 2875);
FORCEPROP 0 LAST CDS_SEC 1
J 0
(-3825 2875);
DISPLAY 0.680851 (-3825 2875);
DISPLAY INVISIBLE (-3825 2875);
FORCEPROP 1 LASTPIN (-3875 2775) $PN 1
J 0
(-3863 2787);
DISPLAY 0.787234 (-3863 2787);
PAINT MONO (-3863 2787);
FORCEPROP 1 LASTPIN (-3675 2775) $PN 2
J 0
(-3713 2787);
DISPLAY 0.787234 (-3713 2787);
PAINT MONO (-3713 2787);
FORCEPROP 1 LAST WATTAGE 1/4W
J 2
(-3800 2625);
DISPLAY 0.978723 (-3800 2625);
FORCEPROP 1 LAST VALUE 0
J 2
(-3800 2675);
DISPLAY 0.978723 (-3800 2675);
FORCEPROP 1 LAST PACK_TYPE 0603LF
J 0
(-3525 2625);
DISPLAY 0.978723 (-3525 2625);
FORCEPROP 1 LAST TOLERANCE 5%
J 0
(-3775 2675);
DISPLAY 0.978723 (-3775 2675);
FORCEPROP 1 LAST MATERIAL CHIP
J 0
(-3775 2625);
DISPLAY 0.978723 (-3775 2625);
FORCEPROP 2 LAST CDS_LIB pure_quanta
J 0
(-3775 2775);
DISPLAY INVISIBLE (-3775 2775);
FORCEPROP 1 LAST PATH I22
J 0
(-3825 2925);
DISPLAY 0.978723 (-3825 2925);
PAINT WHITE (-3825 2925);
DISPLAY INVISIBLE (-3825 2925);
FORCEPROP 1 LAST PART_NUMBER CS00006J900
J 0
(-4000 2550);
DISPLAY 0.978723 (-4000 2550);
DISPLAY INVISIBLE (-4000 2550);
FORCEADD Q_INDUCTOR..1
(-7625 4750);
FORCEPROP 1 LAST LOCATION L18
J 0
(-7750 4910);
DISPLAY 0.723404 (-7750 4910);
PAINT GREEN (-7750 4910);
FORCEPROP 0 LAST $SEC 1
J 0
(-7750 5000);
DISPLAY 0.680851 (-7750 5000);
PAINT MONO (-7750 5000);
DISPLAY INVISIBLE (-7750 5000);
FORCEPROP 0 LAST CDS_SEC 1
J 0
(-7750 5000);
DISPLAY 0.680851 (-7750 5000);
DISPLAY INVISIBLE (-7750 5000);
FORCEPROP 0 LASTPIN (-7725 4725) $PN 1
J 2
(-7735 4735);
DISPLAY 0.680851 (-7735 4735);
PAINT MONO (-7735 4735);
FORCEPROP 0 LASTPIN (-7525 4725) $PN 2
J 0
(-7515 4735);
DISPLAY 0.680851 (-7515 4735);
PAINT MONO (-7515 4735);
FORCEPROP 1 LAST MATERIAL IND
J 0
(-7750 4805);
DISPLAY 0.723404 (-7750 4805);
PAINT GREEN (-7750 4805);
FORCEPROP 2 LAST PACK_TYPE SMLF
J 0
(-7750 4950);
DISPLAY 0.680851 (-7750 4950);
FORCEPROP 2 LAST VALUE BLM21SN300SN1D/5A
J 0
(-7875 4650);
DISPLAY 0.680851 (-7875 4650);
FORCEPROP 2 LAST CDS_LIB pure_quanta
J 0
(-7625 4750);
DISPLAY INVISIBLE (-7625 4750);
FORCEPROP 1 LAST NEEDS_NO_SIZE TRUE
J 0
(-7625 4750);
DISPLAY 0.468085 (-7625 4750);
PAINT GREEN (-7625 4750);
DISPLAY INVISIBLE (-7625 4750);
FORCEPROP 1 LAST PATH I23
J 0
(-7550 4805);
DISPLAY 0.723404 (-7550 4805);
PAINT GREEN (-7550 4805);
DISPLAY INVISIBLE (-7550 4805);
FORCEPROP 1 LAST PART_NUMBER CX300SN1000
J 0
(-7750 4860);
DISPLAY 0.723404 (-7750 4860);
PAINT GREEN (-7750 4860);
DISPLAY INVISIBLE (-7750 4860);
FORCEADD P1V0..1
(-7150 4950);
FORCEPROP 3 LASTPIN (-7150 4900) SIG_NAME P1V8_CPU0_RT2_1A\g
J 0
(-7140 4910);
DISPLAY 0.659574 (-7140 4910);
PAINT MONO (-7140 4910);
DISPLAY INVISIBLE (-7140 4910);
FORCEPROP 1 LAST HDL_POWER P1V8_CPU0_RT2_1A
J 1
(-7150 5000);
DISPLAY 0.489362 (-7150 5000);
PAINT SKYBLUE (-7150 5000);
FORCEPROP 2 LAST CDS_LIB pure_quanta_power
J 0
(-7150 4950);
DISPLAY INVISIBLE (-7150 4950);
FORCEPROP 1 LAST PATH I24
J 0
(-7100 4975);
DISPLAY 0.872340 (-7100 4975);
PAINT AQUA (-7100 4975);
DISPLAY INVISIBLE (-7100 4975);
FORCEADD Q_CAP..1
(-6900 5300);
FORCEPROP 1 LAST LOCATION C665
J 0
(-6850 5400);
DISPLAY 0.638298 (-6850 5400);
PAINT WHITE (-6850 5400);
FORCEPROP 0 LAST $SEC 1
J 0
(-6850 5450);
DISPLAY 0.680851 (-6850 5450);
PAINT MONO (-6850 5450);
DISPLAY INVISIBLE (-6850 5450);
FORCEPROP 0 LAST CDS_SEC 1
J 0
(-6850 5450);
DISPLAY 0.680851 (-6850 5450);
DISPLAY INVISIBLE (-6850 5450);
FORCEPROP 1 LASTPIN (-6900 5400) $PN 1
J 0
(-6890 5380);
DISPLAY 0.787234 (-6890 5380);
PAINT MONO (-6890 5380);
FORCEPROP 1 LASTPIN (-6900 5200) $PN 2
J 0
(-6890 5180);
DISPLAY 0.787234 (-6890 5180);
PAINT MONO (-6890 5180);
FORCEPROP 1 LAST VOLTAGE 4V
J 0
(-6850 5300);
DISPLAY 0.510638 (-6850 5300);
FORCEPROP 1 LAST MATERIAL X6S
J 0
(-6850 5200);
DISPLAY 0.510638 (-6850 5200);
FORCEPROP 1 LAST TOLERANCE 20%
J 0
(-6850 5250);
DISPLAY 0.510638 (-6850 5250);
FORCEPROP 1 LAST VALUE 100UF
J 0
(-6850 5350);
DISPLAY 0.510638 (-6850 5350);
FORCEPROP 1 LAST PACK_TYPE C0805
J 0
(-6850 5150);
DISPLAY 0.510638 (-6850 5150);
FORCEPROP 2 LAST CDS_LIB pure_quanta
J 0
(-6900 5300);
DISPLAY INVISIBLE (-6900 5300);
FORCEPROP 1 LAST PATH I25
J 0
(-6850 5450);
DISPLAY 0.978723 (-6850 5450);
PAINT WHITE (-6850 5450);
DISPLAY INVISIBLE (-6850 5450);
FORCEPROP 1 LAST PART_NUMBER CH710KMEA01
J 0
(-6850 5150);
DISPLAY 0.404255 (-6850 5150);
DISPLAY INVISIBLE (-6850 5150);
FORCEADD Q_CAP..1
(-6400 5275);
FORCEPROP 1 LAST LOCATION C669
J 0
(-6350 5375);
DISPLAY 0.638298 (-6350 5375);
PAINT WHITE (-6350 5375);
FORCEPROP 0 LAST $SEC 1
J 0
(-6350 5425);
DISPLAY 0.680851 (-6350 5425);
PAINT MONO (-6350 5425);
DISPLAY INVISIBLE (-6350 5425);
FORCEPROP 0 LAST CDS_SEC 1
J 0
(-6350 5425);
DISPLAY 0.680851 (-6350 5425);
DISPLAY INVISIBLE (-6350 5425);
FORCEPROP 1 LASTPIN (-6400 5375) $PN 1
J 0
(-6390 5355);
DISPLAY 0.787234 (-6390 5355);
PAINT MONO (-6390 5355);
FORCEPROP 1 LASTPIN (-6400 5175) $PN 2
J 0
(-6390 5155);
DISPLAY 0.787234 (-6390 5155);
PAINT MONO (-6390 5155);
FORCEPROP 1 LAST VALUE 10UF
J 0
(-6350 5325);
DISPLAY 0.510638 (-6350 5325);
FORCEPROP 1 LAST VOLTAGE 6.3V
J 0
(-6350 5275);
DISPLAY 0.510638 (-6350 5275);
FORCEPROP 1 LAST TOLERANCE 20%
J 0
(-6350 5225);
DISPLAY 0.510638 (-6350 5225);
FORCEPROP 1 LAST MATERIAL X6S
J 0
(-6350 5175);
DISPLAY 0.510638 (-6350 5175);
FORCEPROP 1 LAST PACK_TYPE C0402
J 0
(-6350 5125);
DISPLAY 0.510638 (-6350 5125);
FORCEPROP 2 LAST CDS_LIB pure_quanta
J 0
(-6400 5275);
DISPLAY INVISIBLE (-6400 5275);
FORCEPROP 1 LAST PATH I26
J 0
(-6350 5425);
DISPLAY 0.978723 (-6350 5425);
PAINT WHITE (-6350 5425);
DISPLAY INVISIBLE (-6350 5425);
FORCEPROP 1 LAST PART_NUMBER CH6101MEB01
J 0
(-6350 5125);
DISPLAY 0.978723 (-6350 5125);
DISPLAY INVISIBLE (-6350 5125);
FORCEADD Q_CAP..1
(-6650 5300);
FORCEPROP 1 LAST LOCATION C667
J 0
(-6600 5400);
DISPLAY 0.510638 (-6600 5400);
PAINT WHITE (-6600 5400);
FORCEPROP 0 LAST $SEC 1
J 0
(-6600 5425);
DISPLAY 0.680851 (-6600 5425);
PAINT MONO (-6600 5425);
DISPLAY INVISIBLE (-6600 5425);
FORCEPROP 0 LAST CDS_SEC 1
J 0
(-6600 5425);
DISPLAY 0.680851 (-6600 5425);
DISPLAY INVISIBLE (-6600 5425);
FORCEPROP 1 LASTPIN (-6650 5400) $PN 1
J 0
(-6640 5380);
DISPLAY 0.787234 (-6640 5380);
PAINT MONO (-6640 5380);
FORCEPROP 1 LASTPIN (-6650 5200) $PN 2
J 0
(-6640 5180);
DISPLAY 0.787234 (-6640 5180);
PAINT MONO (-6640 5180);
FORCEPROP 1 LAST VALUE 22UF
J 0
(-6600 5350);
DISPLAY 0.510638 (-6600 5350);
FORCEPROP 1 LAST VOLTAGE 4V
J 0
(-6600 5300);
DISPLAY 0.510638 (-6600 5300);
FORCEPROP 1 LAST TOLERANCE 20%
J 0
(-6600 5250);
DISPLAY 0.510638 (-6600 5250);
FORCEPROP 1 LAST MATERIAL X6S
J 0
(-6600 5200);
DISPLAY 0.510638 (-6600 5200);
FORCEPROP 1 LAST PACK_TYPE C0402
J 0
(-6600 5150);
DISPLAY 0.510638 (-6600 5150);
FORCEPROP 2 LAST CDS_LIB pure_quanta
J 0
(-6650 5300);
DISPLAY INVISIBLE (-6650 5300);
FORCEPROP 1 LAST PATH I27
J 0
(-6600 5450);
DISPLAY 0.978723 (-6600 5450);
PAINT WHITE (-6600 5450);
DISPLAY INVISIBLE (-6600 5450);
FORCEPROP 1 LAST PART_NUMBER CH622KMEB02
J 0
(-6600 5150);
DISPLAY 0.978723 (-6600 5150);
DISPLAY INVISIBLE (-6600 5150);
FORCEADD UNIVERSAL_GND..1
(-6225 5000);
FORCEPROP 3 LASTPIN (-6225 5050) SIG_NAME GND\g
J 0
(-6215 5060);
DISPLAY 0.659574 (-6215 5060);
PAINT MONO (-6215 5060);
DISPLAY INVISIBLE (-6215 5060);
FORCEPROP 2 LAST CDS_LIB pure_quanta_power
J 0
(-6225 5000);
DISPLAY INVISIBLE (-6225 5000);
FORCEPROP 1 LAST HDL_POWER GND
J 1
(-6200 4925);
DISPLAY 0.872340 (-6200 4925);
PAINT GREEN (-6200 4925);
DISPLAY INVISIBLE (-6200 4925);
FORCEPROP 1 LAST PATH I28
J 0
(-6150 5000);
DISPLAY 0.872340 (-6150 5000);
PAINT AQUA (-6150 5000);
DISPLAY INVISIBLE (-6150 5000);
FORCEADD Q_CAP..1
(-6150 5275);
FORCEPROP 1 LAST LOCATION C672
J 0
(-6100 5375);
DISPLAY 0.638298 (-6100 5375);
PAINT WHITE (-6100 5375);
FORCEPROP 0 LAST $SEC 1
J 0
(-6100 5425);
DISPLAY 0.680851 (-6100 5425);
PAINT MONO (-6100 5425);
DISPLAY INVISIBLE (-6100 5425);
FORCEPROP 0 LAST CDS_SEC 1
J 0
(-6100 5425);
DISPLAY 0.680851 (-6100 5425);
DISPLAY INVISIBLE (-6100 5425);
FORCEPROP 1 LASTPIN (-6150 5375) $PN 1
J 0
(-6140 5355);
DISPLAY 0.787234 (-6140 5355);
PAINT MONO (-6140 5355);
FORCEPROP 1 LASTPIN (-6150 5175) $PN 2
J 0
(-6140 5155);
DISPLAY 0.787234 (-6140 5155);
PAINT MONO (-6140 5155);
FORCEPROP 1 LAST TOLERANCE 20%
J 0
(-6100 5225);
DISPLAY 0.510638 (-6100 5225);
FORCEPROP 1 LAST VOLTAGE 6.3V
J 0
(-6100 5275);
DISPLAY 0.510638 (-6100 5275);
FORCEPROP 1 LAST VALUE 4.7UF
J 0
(-6100 5325);
DISPLAY 0.510638 (-6100 5325);
FORCEPROP 1 LAST MATERIAL X6S
J 0
(-6100 5175);
DISPLAY 0.510638 (-6100 5175);
FORCEPROP 1 LAST PACK_TYPE 0402
J 0
(-6100 5125);
DISPLAY 0.510638 (-6100 5125);
FORCEPROP 2 LAST CDS_LIB pure_quanta
J 0
(-6150 5275);
DISPLAY INVISIBLE (-6150 5275);
FORCEPROP 1 LAST PATH I29
J 0
(-6100 5425);
DISPLAY 0.978723 (-6100 5425);
PAINT WHITE (-6100 5425);
DISPLAY INVISIBLE (-6100 5425);
FORCEPROP 1 LAST PART_NUMBER CH5471MEB01
J 0
(-6100 5125);
DISPLAY 0.978723 (-6100 5125);
DISPLAY INVISIBLE (-6100 5125);
FORCEADD P1V0..1
(-8000 5575);
FORCEPROP 3 LASTPIN (-8000 5525) SIG_NAME P1V8_CPU0_RT_1D\g
J 0
(-7990 5535);
DISPLAY 0.659574 (-7990 5535);
PAINT MONO (-7990 5535);
DISPLAY INVISIBLE (-7990 5535);
FORCEPROP 1 LAST HDL_POWER P1V8_CPU0_RT_1D
J 1
(-8000 5625);
DISPLAY 0.489362 (-8000 5625);
PAINT SKYBLUE (-8000 5625);
FORCEPROP 2 LAST CDS_LIB pure_quanta_power
J 0
(-8000 5575);
DISPLAY INVISIBLE (-8000 5575);
FORCEPROP 1 LAST PATH I3
J 0
(-7950 5600);
DISPLAY 0.872340 (-7950 5600);
PAINT AQUA (-7950 5600);
DISPLAY INVISIBLE (-7950 5600);
FORCEADD Q_INDUCTOR..1
(-3675 4750);
FORCEPROP 1 LAST LOCATION L21
J 0
(-3800 4910);
DISPLAY 0.723404 (-3800 4910);
PAINT GREEN (-3800 4910);
FORCEPROP 0 LAST $SEC 1
J 0
(-3800 5050);
DISPLAY 0.680851 (-3800 5050);
PAINT MONO (-3800 5050);
DISPLAY INVISIBLE (-3800 5050);
FORCEPROP 0 LAST CDS_SEC 1
J 0
(-3800 5050);
DISPLAY 0.680851 (-3800 5050);
DISPLAY INVISIBLE (-3800 5050);
FORCEPROP 0 LASTPIN (-3775 4725) $PN 1
J 2
(-3785 4735);
DISPLAY 0.680851 (-3785 4735);
PAINT MONO (-3785 4735);
FORCEPROP 0 LASTPIN (-3575 4725) $PN 2
J 0
(-3565 4735);
DISPLAY 0.680851 (-3565 4735);
PAINT MONO (-3565 4735);
FORCEPROP 2 LAST VALUE 100NH/16A
J 0
(-3800 5000);
DISPLAY 0.680851 (-3800 5000);
FORCEPROP 2 LAST PACK_TYPE SMLF
J 0
(-3800 4950);
DISPLAY 0.680851 (-3800 4950);
FORCEPROP 1 LAST MATERIAL IND
J 0
(-3800 4805);
DISPLAY 0.723404 (-3800 4805);
PAINT GREEN (-3800 4805);
FORCEPROP 1 LAST NEEDS_NO_SIZE TRUE
J 0
(-3675 4750);
DISPLAY 0.468085 (-3675 4750);
PAINT GREEN (-3675 4750);
DISPLAY INVISIBLE (-3675 4750);
FORCEPROP 2 LAST CDS_LIB pure_quanta
J 0
(-3675 4750);
DISPLAY INVISIBLE (-3675 4750);
FORCEPROP 1 LAST PATH I30
J 0
(-3600 4805);
DISPLAY 0.723404 (-3600 4805);
PAINT GREEN (-3600 4805);
DISPLAY INVISIBLE (-3600 4805);
FORCEPROP 1 LAST PART_NUMBER CV+10G0MZ04
J 0
(-3800 4860);
DISPLAY 0.723404 (-3800 4860);
PAINT GREEN (-3800 4860);
DISPLAY INVISIBLE (-3800 4860);
FORCEADD VCC_CORE..1
(-4150 6250);
FORCEPROP 3 LASTPIN (-4150 6200) SIG_NAME P0V9_CPU0_RT_2D\g
J 0
(-4140 6210);
DISPLAY 0.659574 (-4140 6210);
PAINT MONO (-4140 6210);
DISPLAY INVISIBLE (-4140 6210);
FORCEPROP 1 LAST HDL_POWER P0V9_CPU0_RT_2D
J 1
(-4150 6300);
DISPLAY 0.617021 (-4150 6300);
PAINT GREEN (-4150 6300);
FORCEPROP 2 LAST CDS_LIB pure_quanta_power
J 0
(-4150 6250);
DISPLAY INVISIBLE (-4150 6250);
FORCEPROP 1 LAST PATH I31
J 0
(-4100 6275);
DISPLAY 0.872340 (-4100 6275);
PAINT AQUA (-4100 6275);
DISPLAY INVISIBLE (-4100 6275);
FORCEADD VCC_CORE..1
(-3000 1950);
FORCEPROP 3 LASTPIN (-3000 1900) SIG_NAME P0V9_CPU0_RT2_2A_2D\g
J 0
(-2990 1910);
DISPLAY 0.659574 (-2990 1910);
PAINT MONO (-2990 1910);
DISPLAY INVISIBLE (-2990 1910);
FORCEPROP 1 LAST HDL_POWER P0V9_CPU0_RT2_2A_2D
J 1
(-3000 2000);
DISPLAY 0.617021 (-3000 2000);
PAINT GREEN (-3000 2000);
FORCEPROP 2 LAST CDS_LIB pure_quanta_power
J 0
(-3000 1950);
DISPLAY INVISIBLE (-3000 1950);
FORCEPROP 1 LAST PATH I33
J 0
(-2950 1975);
DISPLAY 0.872340 (-2950 1975);
PAINT AQUA (-2950 1975);
DISPLAY INVISIBLE (-2950 1975);
FORCEADD Q_CAP..1
(-3050 2525);
FORCEPROP 1 LAST LOCATION C982
J 0
(-3000 2625);
DISPLAY 0.978723 (-3000 2625);
PAINT WHITE (-3000 2625);
FORCEPROP 0 LAST $SEC 1
J 0
(-3000 2675);
DISPLAY 0.680851 (-3000 2675);
PAINT MONO (-3000 2675);
DISPLAY INVISIBLE (-3000 2675);
FORCEPROP 0 LAST CDS_SEC 1
J 0
(-3000 2675);
DISPLAY 0.680851 (-3000 2675);
DISPLAY INVISIBLE (-3000 2675);
FORCEPROP 1 LASTPIN (-3050 2625) $PN 1
J 0
(-3040 2605);
DISPLAY 0.787234 (-3040 2605);
PAINT MONO (-3040 2605);
FORCEPROP 1 LASTPIN (-3050 2425) $PN 2
J 0
(-3040 2405);
DISPLAY 0.787234 (-3040 2405);
PAINT MONO (-3040 2405);
FORCEPROP 1 LAST MATERIAL X7S
J 0
(-3000 2425);
DISPLAY 0.638298 (-3000 2425);
FORCEPROP 1 LAST TOLERANCE 10%
J 0
(-3000 2475);
DISPLAY 0.638298 (-3000 2475);
FORCEPROP 1 LAST PACK_TYPE C0201
J 0
(-3000 2375);
DISPLAY 0.638298 (-3000 2375);
FORCEPROP 1 LAST VOLTAGE 10V
J 0
(-3000 2525);
DISPLAY 0.638298 (-3000 2525);
FORCEPROP 1 LAST VALUE 0.1UF
J 0
(-3000 2575);
DISPLAY 0.638298 (-3000 2575);
FORCEPROP 2 LAST CDS_LIB pure_quanta
J 0
(-3050 2525);
DISPLAY INVISIBLE (-3050 2525);
FORCEPROP 1 LAST PATH I34
J 0
(-3000 2675);
DISPLAY 0.978723 (-3000 2675);
PAINT WHITE (-3000 2675);
DISPLAY INVISIBLE (-3000 2675);
FORCEPROP 1 LAST PART_NUMBER CH4102K6E00
J 0
(-3000 2375);
DISPLAY 0.978723 (-3000 2375);
DISPLAY INVISIBLE (-3000 2375);
FORCEADD Q_CAP..1
(-2750 2525);
FORCEPROP 1 LAST LOCATION C984
J 0
(-2700 2625);
DISPLAY 0.978723 (-2700 2625);
PAINT WHITE (-2700 2625);
FORCEPROP 0 LAST $SEC 1
J 0
(-2700 2675);
DISPLAY 0.680851 (-2700 2675);
PAINT MONO (-2700 2675);
DISPLAY INVISIBLE (-2700 2675);
FORCEPROP 0 LAST CDS_SEC 1
J 0
(-2700 2675);
DISPLAY 0.680851 (-2700 2675);
DISPLAY INVISIBLE (-2700 2675);
FORCEPROP 1 LASTPIN (-2750 2625) $PN 1
J 0
(-2740 2605);
DISPLAY 0.787234 (-2740 2605);
PAINT MONO (-2740 2605);
FORCEPROP 1 LASTPIN (-2750 2425) $PN 2
J 0
(-2740 2405);
DISPLAY 0.787234 (-2740 2405);
PAINT MONO (-2740 2405);
FORCEPROP 1 LAST VOLTAGE 10V
J 0
(-2700 2525);
DISPLAY 0.638298 (-2700 2525);
FORCEPROP 1 LAST VALUE 0.1UF
J 0
(-2700 2575);
DISPLAY 0.638298 (-2700 2575);
FORCEPROP 1 LAST PACK_TYPE C0201
J 0
(-2700 2375);
DISPLAY 0.638298 (-2700 2375);
FORCEPROP 1 LAST MATERIAL X7S
J 0
(-2700 2425);
DISPLAY 0.638298 (-2700 2425);
FORCEPROP 1 LAST TOLERANCE 10%
J 0
(-2700 2475);
DISPLAY 0.638298 (-2700 2475);
FORCEPROP 2 LAST CDS_LIB pure_quanta
J 0
(-2750 2525);
DISPLAY INVISIBLE (-2750 2525);
FORCEPROP 1 LAST PATH I35
J 0
(-2700 2675);
DISPLAY 0.978723 (-2700 2675);
PAINT WHITE (-2700 2675);
DISPLAY INVISIBLE (-2700 2675);
FORCEPROP 1 LAST PART_NUMBER CH4102K6E00
J 0
(-2700 2375);
DISPLAY 0.978723 (-2700 2375);
DISPLAY INVISIBLE (-2700 2375);
FORCEADD Q_CAP..1
(-2625 1425);
FORCEPROP 1 LAST LOCATION C791
J 0
(-2575 1525);
DISPLAY 0.978723 (-2575 1525);
PAINT WHITE (-2575 1525);
FORCEPROP 0 LAST $SEC 1
J 0
(-2575 1575);
DISPLAY 0.680851 (-2575 1575);
PAINT MONO (-2575 1575);
DISPLAY INVISIBLE (-2575 1575);
FORCEPROP 0 LAST CDS_SEC 1
J 0
(-2575 1575);
DISPLAY 0.680851 (-2575 1575);
DISPLAY INVISIBLE (-2575 1575);
FORCEPROP 1 LASTPIN (-2625 1525) $PN 1
J 0
(-2615 1505);
DISPLAY 0.787234 (-2615 1505);
PAINT MONO (-2615 1505);
FORCEPROP 1 LASTPIN (-2625 1325) $PN 2
J 0
(-2615 1305);
DISPLAY 0.787234 (-2615 1305);
PAINT MONO (-2615 1305);
FORCEPROP 1 LAST VALUE 0.1UF
J 0
(-2575 1475);
DISPLAY 0.638298 (-2575 1475);
FORCEPROP 1 LAST PACK_TYPE C0201
J 0
(-2575 1275);
DISPLAY 0.638298 (-2575 1275);
FORCEPROP 1 LAST VOLTAGE 10V
J 0
(-2575 1425);
DISPLAY 0.638298 (-2575 1425);
FORCEPROP 1 LAST TOLERANCE 10%
J 0
(-2575 1375);
DISPLAY 0.638298 (-2575 1375);
FORCEPROP 1 LAST MATERIAL X7S
J 0
(-2575 1325);
DISPLAY 0.638298 (-2575 1325);
FORCEPROP 2 LAST CDS_LIB pure_quanta
J 0
(-2625 1425);
DISPLAY INVISIBLE (-2625 1425);
FORCEPROP 1 LAST PATH I36
J 0
(-2575 1575);
DISPLAY 0.978723 (-2575 1575);
PAINT WHITE (-2575 1575);
DISPLAY INVISIBLE (-2575 1575);
FORCEPROP 1 LAST PART_NUMBER CH4102K6E00
J 0
(-2575 1275);
DISPLAY 0.978723 (-2575 1275);
DISPLAY INVISIBLE (-2575 1275);
FORCEADD UNIVERSAL_GND..1
(-2175 1100);
FORCEPROP 3 LASTPIN (-2175 1150) SIG_NAME GND\g
J 0
(-2165 1160);
DISPLAY 0.659574 (-2165 1160);
PAINT MONO (-2165 1160);
DISPLAY INVISIBLE (-2165 1160);
FORCEPROP 2 LAST CDS_LIB pure_quanta_power
J 0
(-2175 1100);
DISPLAY INVISIBLE (-2175 1100);
FORCEPROP 1 LAST HDL_POWER GND
J 1
(-2150 1025);
DISPLAY 0.872340 (-2150 1025);
PAINT GREEN (-2150 1025);
DISPLAY INVISIBLE (-2150 1025);
FORCEPROP 1 LAST PATH I38
J 0
(-2100 1100);
DISPLAY 0.872340 (-2100 1100);
PAINT AQUA (-2100 1100);
DISPLAY INVISIBLE (-2100 1100);
FORCEADD Q_CAP..1
(-2075 1425);
FORCEPROP 1 LAST LOCATION C794
J 0
(-2025 1525);
DISPLAY 0.978723 (-2025 1525);
PAINT WHITE (-2025 1525);
FORCEPROP 0 LAST $SEC 1
J 0
(-2025 1575);
DISPLAY 0.680851 (-2025 1575);
PAINT MONO (-2025 1575);
DISPLAY INVISIBLE (-2025 1575);
FORCEPROP 0 LAST CDS_SEC 1
J 0
(-2025 1575);
DISPLAY 0.680851 (-2025 1575);
DISPLAY INVISIBLE (-2025 1575);
FORCEPROP 1 LASTPIN (-2075 1525) $PN 1
J 0
(-2065 1505);
DISPLAY 0.787234 (-2065 1505);
PAINT MONO (-2065 1505);
FORCEPROP 1 LASTPIN (-2075 1325) $PN 2
J 0
(-2065 1305);
DISPLAY 0.787234 (-2065 1305);
PAINT MONO (-2065 1305);
FORCEPROP 1 LAST VALUE 0.1UF
J 0
(-2025 1475);
DISPLAY 0.638298 (-2025 1475);
FORCEPROP 1 LAST TOLERANCE 10%
J 0
(-2025 1375);
DISPLAY 0.638298 (-2025 1375);
FORCEPROP 1 LAST VOLTAGE 10V
J 0
(-2025 1425);
DISPLAY 0.638298 (-2025 1425);
FORCEPROP 1 LAST PACK_TYPE C0201
J 0
(-2025 1275);
DISPLAY 0.638298 (-2025 1275);
FORCEPROP 1 LAST MATERIAL X7S
J 0
(-2025 1325);
DISPLAY 0.638298 (-2025 1325);
FORCEPROP 2 LAST CDS_LIB pure_quanta
J 0
(-2075 1425);
DISPLAY INVISIBLE (-2075 1425);
FORCEPROP 1 LAST PATH I39
J 0
(-2025 1575);
DISPLAY 0.978723 (-2025 1575);
PAINT WHITE (-2025 1575);
DISPLAY INVISIBLE (-2025 1575);
FORCEPROP 1 LAST PART_NUMBER CH4102K6E00
J 0
(-2025 1275);
DISPLAY 0.978723 (-2025 1275);
DISPLAY INVISIBLE (-2025 1275);
FORCEADD Q_RES..1
(-7550 3850);
FORCEPROP 1 LAST LOCATION R1046
J 0
(-7825 3850);
DISPLAY 0.787234 (-7825 3850);
FORCEPROP 2 LAST SEC 1
J 0
(-7600 4050);
DISPLAY 0.680851 (-7600 4050);
PAINT MONO (-7600 4050);
DISPLAY INVISIBLE (-7600 4050);
FORCEPROP 1 LASTPIN (-7650 3850) $PN 1
J 0
(-7638 3862);
DISPLAY 0.787234 (-7638 3862);
PAINT MONO (-7638 3862);
FORCEPROP 1 LASTPIN (-7450 3850) $PN 2
J 0
(-7488 3862);
DISPLAY 0.787234 (-7488 3862);
PAINT MONO (-7488 3862);
FORCEPROP 1 LAST TOLERANCE 5%
J 0
(-7500 3800);
DISPLAY 0.638298 (-7500 3800);
FORCEPROP 1 LAST PACK_TYPE 0402LF
J 0
(-7700 3800);
DISPLAY 0.638298 (-7700 3800);
FORCEPROP 1 LAST VALUE 0
J 2
(-7400 3875);
DISPLAY 0.638298 (-7400 3875);
FORCEPROP 1 LAST MATERIAL EMPTY
J 0
(-7525 3750);
DISPLAY 0.638298 (-7525 3750);
FORCEPROP 1 LAST WATTAGE 1/16W
J 2
(-7550 3750);
DISPLAY 0.638298 (-7550 3750);
FORCEPROP 2 LAST CDS_LIB pure_quanta
J 0
(-7550 3850);
DISPLAY INVISIBLE (-7550 3850);
FORCEPROP 2 LAST SEC_TYPE 0402LF
J 0
(-7600 4050);
DISPLAY 0.680851 (-7600 4050);
DISPLAY INVISIBLE (-7600 4050);
FORCEPROP 1 LAST PATH I4
J 0
(-7600 4000);
DISPLAY 0.978723 (-7600 4000);
PAINT WHITE (-7600 4000);
DISPLAY INVISIBLE (-7600 4000);
FORCEPROP 1 LAST PART_NUMBER CS00002JB13
J 0
(-7600 3950);
DISPLAY 0.978723 (-7600 3950);
DISPLAY INVISIBLE (-7600 3950);
FORCEADD Q_CAP..1
(-2525 2525);
FORCEPROP 1 LAST LOCATION C790
J 0
(-2475 2625);
DISPLAY 0.978723 (-2475 2625);
PAINT WHITE (-2475 2625);
FORCEPROP 0 LAST $SEC 1
J 0
(-2475 2675);
DISPLAY 0.680851 (-2475 2675);
PAINT MONO (-2475 2675);
DISPLAY INVISIBLE (-2475 2675);
FORCEPROP 0 LAST CDS_SEC 1
J 0
(-2475 2675);
DISPLAY 0.680851 (-2475 2675);
DISPLAY INVISIBLE (-2475 2675);
FORCEPROP 1 LASTPIN (-2525 2625) $PN 1
J 0
(-2515 2605);
DISPLAY 0.787234 (-2515 2605);
PAINT MONO (-2515 2605);
FORCEPROP 1 LASTPIN (-2525 2425) $PN 2
J 0
(-2515 2405);
DISPLAY 0.787234 (-2515 2405);
PAINT MONO (-2515 2405);
FORCEPROP 1 LAST TOLERANCE 10%
J 0
(-2475 2475);
DISPLAY 0.638298 (-2475 2475);
FORCEPROP 1 LAST VALUE 0.1UF
J 0
(-2475 2575);
DISPLAY 0.638298 (-2475 2575);
FORCEPROP 1 LAST VOLTAGE 10V
J 0
(-2475 2525);
DISPLAY 0.638298 (-2475 2525);
FORCEPROP 1 LAST MATERIAL X7S
J 0
(-2475 2425);
DISPLAY 0.638298 (-2475 2425);
FORCEPROP 1 LAST PACK_TYPE C0201
J 0
(-2475 2375);
DISPLAY 0.638298 (-2475 2375);
FORCEPROP 2 LAST CDS_LIB pure_quanta
J 0
(-2525 2525);
DISPLAY INVISIBLE (-2525 2525);
FORCEPROP 1 LAST PATH I40
J 0
(-2475 2675);
DISPLAY 0.978723 (-2475 2675);
PAINT WHITE (-2475 2675);
DISPLAY INVISIBLE (-2475 2675);
FORCEPROP 1 LAST PART_NUMBER CH4102K6E00
J 0
(-2475 2375);
DISPLAY 0.978723 (-2475 2375);
DISPLAY INVISIBLE (-2475 2375);
FORCEADD Q_CAP..1
(-2275 2525);
FORCEPROP 1 LAST LOCATION C987
J 0
(-2225 2625);
DISPLAY 0.978723 (-2225 2625);
PAINT WHITE (-2225 2625);
FORCEPROP 0 LAST $SEC 1
J 0
(-2225 2675);
DISPLAY 0.680851 (-2225 2675);
PAINT MONO (-2225 2675);
DISPLAY INVISIBLE (-2225 2675);
FORCEPROP 0 LAST CDS_SEC 1
J 0
(-2225 2675);
DISPLAY 0.680851 (-2225 2675);
DISPLAY INVISIBLE (-2225 2675);
FORCEPROP 1 LASTPIN (-2275 2625) $PN 1
J 0
(-2265 2605);
DISPLAY 0.787234 (-2265 2605);
PAINT MONO (-2265 2605);
FORCEPROP 1 LASTPIN (-2275 2425) $PN 2
J 0
(-2265 2405);
DISPLAY 0.787234 (-2265 2405);
PAINT MONO (-2265 2405);
FORCEPROP 1 LAST PACK_TYPE C0201
J 0
(-2225 2375);
DISPLAY 0.638298 (-2225 2375);
FORCEPROP 1 LAST TOLERANCE 10%
J 0
(-2225 2475);
DISPLAY 0.638298 (-2225 2475);
FORCEPROP 1 LAST MATERIAL X7S
J 0
(-2225 2425);
DISPLAY 0.638298 (-2225 2425);
FORCEPROP 1 LAST VOLTAGE 10V
J 0
(-2225 2525);
DISPLAY 0.638298 (-2225 2525);
FORCEPROP 1 LAST VALUE 0.1UF
J 0
(-2225 2575);
DISPLAY 0.638298 (-2225 2575);
FORCEPROP 2 LAST CDS_LIB pure_quanta
J 0
(-2275 2525);
DISPLAY INVISIBLE (-2275 2525);
FORCEPROP 1 LAST PATH I41
J 0
(-2225 2675);
DISPLAY 0.978723 (-2225 2675);
PAINT WHITE (-2225 2675);
DISPLAY INVISIBLE (-2225 2675);
FORCEPROP 1 LAST PART_NUMBER CH4102K6E00
J 0
(-2225 2375);
DISPLAY 0.978723 (-2225 2375);
DISPLAY INVISIBLE (-2225 2375);
FORCEADD Q_CAP..1
(-2025 2525);
FORCEPROP 1 LAST LOCATION C800
J 0
(-1975 2625);
DISPLAY 0.978723 (-1975 2625);
PAINT WHITE (-1975 2625);
FORCEPROP 0 LAST $SEC 1
J 0
(-1975 2675);
DISPLAY 0.680851 (-1975 2675);
PAINT MONO (-1975 2675);
DISPLAY INVISIBLE (-1975 2675);
FORCEPROP 0 LAST CDS_SEC 1
J 0
(-1975 2675);
DISPLAY 0.680851 (-1975 2675);
DISPLAY INVISIBLE (-1975 2675);
FORCEPROP 1 LASTPIN (-2025 2625) $PN 1
J 0
(-2015 2605);
DISPLAY 0.787234 (-2015 2605);
PAINT MONO (-2015 2605);
FORCEPROP 1 LASTPIN (-2025 2425) $PN 2
J 0
(-2015 2405);
DISPLAY 0.787234 (-2015 2405);
PAINT MONO (-2015 2405);
FORCEPROP 1 LAST PACK_TYPE C0201
J 0
(-1975 2375);
DISPLAY 0.638298 (-1975 2375);
FORCEPROP 1 LAST VOLTAGE 10V
J 0
(-1975 2525);
DISPLAY 0.638298 (-1975 2525);
FORCEPROP 1 LAST VALUE 0.1UF
J 0
(-1975 2575);
DISPLAY 0.638298 (-1975 2575);
FORCEPROP 1 LAST MATERIAL X7S
J 0
(-1975 2425);
DISPLAY 0.638298 (-1975 2425);
FORCEPROP 1 LAST TOLERANCE 10%
J 0
(-1975 2475);
DISPLAY 0.638298 (-1975 2475);
FORCEPROP 2 LAST CDS_LIB pure_quanta
J 0
(-2025 2525);
DISPLAY INVISIBLE (-2025 2525);
FORCEPROP 1 LAST PATH I42
J 0
(-1975 2675);
DISPLAY 0.978723 (-1975 2675);
PAINT WHITE (-1975 2675);
DISPLAY INVISIBLE (-1975 2675);
FORCEPROP 1 LAST PART_NUMBER CH4102K6E00
J 0
(-1975 2375);
DISPLAY 0.978723 (-1975 2375);
DISPLAY INVISIBLE (-1975 2375);
FORCEADD Q_CAP..1
(-1750 2525);
FORCEPROP 1 LAST LOCATION C784
J 0
(-1700 2625);
DISPLAY 0.978723 (-1700 2625);
PAINT WHITE (-1700 2625);
FORCEPROP 0 LAST $SEC 1
J 0
(-1700 2675);
DISPLAY 0.680851 (-1700 2675);
PAINT MONO (-1700 2675);
DISPLAY INVISIBLE (-1700 2675);
FORCEPROP 0 LAST CDS_SEC 1
J 0
(-1700 2675);
DISPLAY 0.680851 (-1700 2675);
DISPLAY INVISIBLE (-1700 2675);
FORCEPROP 1 LASTPIN (-1750 2625) $PN 1
J 0
(-1740 2605);
DISPLAY 0.787234 (-1740 2605);
PAINT MONO (-1740 2605);
FORCEPROP 1 LASTPIN (-1750 2425) $PN 2
J 0
(-1740 2405);
DISPLAY 0.787234 (-1740 2405);
PAINT MONO (-1740 2405);
FORCEPROP 1 LAST VALUE 0.1UF
J 0
(-1700 2575);
DISPLAY 0.638298 (-1700 2575);
FORCEPROP 1 LAST VOLTAGE 10V
J 0
(-1700 2525);
DISPLAY 0.638298 (-1700 2525);
FORCEPROP 1 LAST MATERIAL X7S
J 0
(-1700 2425);
DISPLAY 0.638298 (-1700 2425);
FORCEPROP 1 LAST PACK_TYPE C0201
J 0
(-1700 2375);
DISPLAY 0.638298 (-1700 2375);
FORCEPROP 1 LAST TOLERANCE 10%
J 0
(-1700 2475);
DISPLAY 0.638298 (-1700 2475);
FORCEPROP 2 LAST CDS_LIB pure_quanta
J 0
(-1750 2525);
DISPLAY INVISIBLE (-1750 2525);
FORCEPROP 1 LAST PATH I43
J 0
(-1700 2675);
DISPLAY 0.978723 (-1700 2675);
PAINT WHITE (-1700 2675);
DISPLAY INVISIBLE (-1700 2675);
FORCEPROP 1 LAST PART_NUMBER CH4102K6E00
J 0
(-1700 2375);
DISPLAY 0.978723 (-1700 2375);
DISPLAY INVISIBLE (-1700 2375);
FORCEADD Q_CAP..1
(-3325 3225);
FORCEPROP 1 LAST LOCATION C797
J 0
(-3275 3325);
DISPLAY 0.978723 (-3275 3325);
PAINT WHITE (-3275 3325);
FORCEPROP 0 LAST $SEC 1
J 0
(-3275 3375);
DISPLAY 0.680851 (-3275 3375);
PAINT MONO (-3275 3375);
DISPLAY INVISIBLE (-3275 3375);
FORCEPROP 0 LAST CDS_SEC 1
J 0
(-3275 3375);
DISPLAY 0.680851 (-3275 3375);
DISPLAY INVISIBLE (-3275 3375);
FORCEPROP 1 LASTPIN (-3325 3325) $PN 1
J 0
(-3315 3305);
DISPLAY 0.787234 (-3315 3305);
PAINT MONO (-3315 3305);
FORCEPROP 1 LASTPIN (-3325 3125) $PN 2
J 0
(-3315 3105);
DISPLAY 0.787234 (-3315 3105);
PAINT MONO (-3315 3105);
FORCEPROP 1 LAST PACK_TYPE 0201
J 0
(-3275 3075);
DISPLAY 0.510638 (-3275 3075);
FORCEPROP 1 LAST TOLERANCE 20%
J 0
(-3275 3175);
DISPLAY 0.510638 (-3275 3175);
FORCEPROP 1 LAST MATERIAL X6S
J 0
(-3275 3125);
DISPLAY 0.510638 (-3275 3125);
FORCEPROP 1 LAST VALUE 1UF
J 0
(-3275 3275);
DISPLAY 0.510638 (-3275 3275);
FORCEPROP 1 LAST VOLTAGE 4V
J 0
(-3275 3225);
DISPLAY 0.510638 (-3275 3225);
FORCEPROP 2 LAST CDS_LIB pure_quanta
J 0
(-3325 3225);
DISPLAY INVISIBLE (-3325 3225);
FORCEPROP 1 LAST PATH I44
J 0
(-3275 3375);
DISPLAY 0.978723 (-3275 3375);
PAINT WHITE (-3275 3375);
DISPLAY INVISIBLE (-3275 3375);
FORCEPROP 1 LAST PART_NUMBER CH-10KMEE00
J 0
(-3275 3075);
DISPLAY 0.510638 (-3275 3075);
DISPLAY INVISIBLE (-3275 3075);
FORCEADD Q_CAP..1
(-3100 3225);
FORCEPROP 1 LAST LOCATION C781
J 0
(-3050 3325);
DISPLAY 0.978723 (-3050 3325);
PAINT WHITE (-3050 3325);
FORCEPROP 0 LAST $SEC 1
J 0
(-3050 3375);
DISPLAY 0.680851 (-3050 3375);
PAINT MONO (-3050 3375);
DISPLAY INVISIBLE (-3050 3375);
FORCEPROP 0 LAST CDS_SEC 1
J 0
(-3050 3375);
DISPLAY 0.680851 (-3050 3375);
DISPLAY INVISIBLE (-3050 3375);
FORCEPROP 1 LASTPIN (-3100 3325) $PN 1
J 0
(-3090 3305);
DISPLAY 0.787234 (-3090 3305);
PAINT MONO (-3090 3305);
FORCEPROP 1 LASTPIN (-3100 3125) $PN 2
J 0
(-3090 3105);
DISPLAY 0.787234 (-3090 3105);
PAINT MONO (-3090 3105);
FORCEPROP 1 LAST TOLERANCE 20%
J 0
(-3050 3175);
DISPLAY 0.510638 (-3050 3175);
FORCEPROP 1 LAST VOLTAGE 4V
J 0
(-3050 3225);
DISPLAY 0.510638 (-3050 3225);
FORCEPROP 1 LAST VALUE 1UF
J 0
(-3050 3275);
DISPLAY 0.510638 (-3050 3275);
FORCEPROP 1 LAST PACK_TYPE 0201
J 0
(-3050 3075);
DISPLAY 0.510638 (-3050 3075);
FORCEPROP 1 LAST MATERIAL X6S
J 0
(-3050 3125);
DISPLAY 0.510638 (-3050 3125);
FORCEPROP 2 LAST CDS_LIB pure_quanta
J 0
(-3100 3225);
DISPLAY INVISIBLE (-3100 3225);
FORCEPROP 1 LAST PATH I45
J 0
(-3050 3375);
DISPLAY 0.978723 (-3050 3375);
PAINT WHITE (-3050 3375);
DISPLAY INVISIBLE (-3050 3375);
FORCEPROP 1 LAST PART_NUMBER CH-10KMEE00
J 0
(-3050 3075);
DISPLAY 0.510638 (-3050 3075);
DISPLAY INVISIBLE (-3050 3075);
FORCEADD Q_CAP..1
(-2850 3225);
FORCEPROP 1 LAST LOCATION C788
J 0
(-2800 3325);
DISPLAY 0.978723 (-2800 3325);
PAINT WHITE (-2800 3325);
FORCEPROP 0 LAST $SEC 1
J 0
(-2800 3375);
DISPLAY 0.680851 (-2800 3375);
PAINT MONO (-2800 3375);
DISPLAY INVISIBLE (-2800 3375);
FORCEPROP 0 LAST CDS_SEC 1
J 0
(-2800 3375);
DISPLAY 0.680851 (-2800 3375);
DISPLAY INVISIBLE (-2800 3375);
FORCEPROP 1 LASTPIN (-2850 3325) $PN 1
J 0
(-2840 3305);
DISPLAY 0.787234 (-2840 3305);
PAINT MONO (-2840 3305);
FORCEPROP 1 LASTPIN (-2850 3125) $PN 2
J 0
(-2840 3105);
DISPLAY 0.787234 (-2840 3105);
PAINT MONO (-2840 3105);
FORCEPROP 1 LAST PACK_TYPE 0201
J 0
(-2800 3075);
DISPLAY 0.510638 (-2800 3075);
FORCEPROP 1 LAST TOLERANCE 20%
J 0
(-2800 3175);
DISPLAY 0.510638 (-2800 3175);
FORCEPROP 1 LAST VALUE 1UF
J 0
(-2800 3275);
DISPLAY 0.510638 (-2800 3275);
FORCEPROP 1 LAST VOLTAGE 4V
J 0
(-2800 3225);
DISPLAY 0.510638 (-2800 3225);
FORCEPROP 1 LAST MATERIAL X6S
J 0
(-2800 3125);
DISPLAY 0.510638 (-2800 3125);
FORCEPROP 2 LAST CDS_LIB pure_quanta
J 0
(-2850 3225);
DISPLAY INVISIBLE (-2850 3225);
FORCEPROP 1 LAST PATH I46
J 0
(-2800 3375);
DISPLAY 0.978723 (-2800 3375);
PAINT WHITE (-2800 3375);
DISPLAY INVISIBLE (-2800 3375);
FORCEPROP 1 LAST PART_NUMBER CH-10KMEE00
J 0
(-2800 3075);
DISPLAY 0.510638 (-2800 3075);
DISPLAY INVISIBLE (-2800 3075);
FORCEADD Q_CAP..1
(-3325 3850);
FORCEPROP 1 LAST LOCATION C796
J 0
(-3275 3950);
DISPLAY 0.978723 (-3275 3950);
PAINT WHITE (-3275 3950);
FORCEPROP 0 LAST $SEC 1
J 0
(-3275 4000);
DISPLAY 0.680851 (-3275 4000);
PAINT MONO (-3275 4000);
DISPLAY INVISIBLE (-3275 4000);
FORCEPROP 0 LAST CDS_SEC 1
J 0
(-3275 4000);
DISPLAY 0.680851 (-3275 4000);
DISPLAY INVISIBLE (-3275 4000);
FORCEPROP 1 LASTPIN (-3325 3950) $PN 1
J 0
(-3315 3930);
DISPLAY 0.787234 (-3315 3930);
PAINT MONO (-3315 3930);
FORCEPROP 1 LASTPIN (-3325 3750) $PN 2
J 0
(-3315 3730);
DISPLAY 0.787234 (-3315 3730);
PAINT MONO (-3315 3730);
FORCEPROP 1 LAST MATERIAL X6S
J 0
(-3275 3750);
DISPLAY 0.510638 (-3275 3750);
FORCEPROP 1 LAST VOLTAGE 6.3V
J 0
(-3275 3850);
DISPLAY 0.510638 (-3275 3850);
FORCEPROP 1 LAST TOLERANCE 20%
J 0
(-3275 3800);
DISPLAY 0.510638 (-3275 3800);
FORCEPROP 1 LAST PACK_TYPE C0402
J 0
(-3275 3700);
DISPLAY 0.510638 (-3275 3700);
FORCEPROP 1 LAST VALUE 10UF
J 0
(-3275 3900);
DISPLAY 0.510638 (-3275 3900);
FORCEPROP 2 LAST CDS_LIB pure_quanta
J 0
(-3325 3850);
DISPLAY INVISIBLE (-3325 3850);
FORCEPROP 1 LAST PATH I47
J 0
(-3275 4000);
DISPLAY 0.978723 (-3275 4000);
PAINT WHITE (-3275 4000);
DISPLAY INVISIBLE (-3275 4000);
FORCEPROP 1 LAST PART_NUMBER CH6101MEB01
J 0
(-3275 3700);
DISPLAY 0.978723 (-3275 3700);
DISPLAY INVISIBLE (-3275 3700);
FORCEADD Q_CAP..1
(-3325 4475);
FORCEPROP 1 LAST LOCATION C795
J 0
(-3275 4575);
DISPLAY 0.978723 (-3275 4575);
PAINT WHITE (-3275 4575);
FORCEPROP 0 LAST $SEC 1
J 0
(-3275 4625);
DISPLAY 0.680851 (-3275 4625);
PAINT MONO (-3275 4625);
DISPLAY INVISIBLE (-3275 4625);
FORCEPROP 0 LAST CDS_SEC 1
J 0
(-3275 4625);
DISPLAY 0.680851 (-3275 4625);
DISPLAY INVISIBLE (-3275 4625);
FORCEPROP 1 LASTPIN (-3325 4575) $PN 1
J 0
(-3315 4555);
DISPLAY 0.787234 (-3315 4555);
PAINT MONO (-3315 4555);
FORCEPROP 1 LASTPIN (-3325 4375) $PN 2
J 0
(-3315 4355);
DISPLAY 0.787234 (-3315 4355);
PAINT MONO (-3315 4355);
FORCEPROP 1 LAST PACK_TYPE C0805
J 0
(-3275 4325);
DISPLAY 0.510638 (-3275 4325);
FORCEPROP 1 LAST VOLTAGE 4V
J 0
(-3275 4475);
DISPLAY 0.510638 (-3275 4475);
FORCEPROP 1 LAST TOLERANCE 20%
J 0
(-3275 4425);
DISPLAY 0.510638 (-3275 4425);
FORCEPROP 1 LAST VALUE 100UF
J 0
(-3275 4525);
DISPLAY 0.510638 (-3275 4525);
FORCEPROP 1 LAST MATERIAL X6S
J 0
(-3275 4375);
DISPLAY 0.510638 (-3275 4375);
FORCEPROP 2 LAST CDS_LIB pure_quanta
J 0
(-3325 4475);
DISPLAY INVISIBLE (-3325 4475);
FORCEPROP 1 LAST PATH I48
J 0
(-3275 4625);
DISPLAY 0.978723 (-3275 4625);
PAINT WHITE (-3275 4625);
DISPLAY INVISIBLE (-3275 4625);
FORCEPROP 1 LAST PART_NUMBER CH710KMEA01
J 0
(-3275 4325);
DISPLAY 0.404255 (-3275 4325);
DISPLAY INVISIBLE (-3275 4325);
FORCEADD Q_CAP..1
(-2875 3850);
FORCEPROP 1 LAST LOCATION C981
J 0
(-2825 3950);
DISPLAY 0.978723 (-2825 3950);
PAINT WHITE (-2825 3950);
FORCEPROP 0 LAST $SEC 1
J 0
(-2825 4000);
DISPLAY 0.680851 (-2825 4000);
PAINT MONO (-2825 4000);
DISPLAY INVISIBLE (-2825 4000);
FORCEPROP 0 LAST CDS_SEC 1
J 0
(-2825 4000);
DISPLAY 0.680851 (-2825 4000);
DISPLAY INVISIBLE (-2825 4000);
FORCEPROP 1 LASTPIN (-2875 3950) $PN 1
J 0
(-2865 3930);
DISPLAY 0.787234 (-2865 3930);
PAINT MONO (-2865 3930);
FORCEPROP 1 LASTPIN (-2875 3750) $PN 2
J 0
(-2865 3730);
DISPLAY 0.787234 (-2865 3730);
PAINT MONO (-2865 3730);
FORCEPROP 1 LAST TOLERANCE 20%
J 0
(-2825 3800);
DISPLAY 0.510638 (-2825 3800);
FORCEPROP 1 LAST MATERIAL X6S
J 0
(-2825 3750);
DISPLAY 0.510638 (-2825 3750);
FORCEPROP 1 LAST VOLTAGE 6.3V
J 0
(-2825 3850);
DISPLAY 0.510638 (-2825 3850);
FORCEPROP 1 LAST VALUE 4.7UF
J 0
(-2825 3900);
DISPLAY 0.510638 (-2825 3900);
FORCEPROP 1 LAST PACK_TYPE 0402
J 0
(-2825 3700);
DISPLAY 0.510638 (-2825 3700);
FORCEPROP 2 LAST CDS_LIB pure_quanta
J 0
(-2875 3850);
DISPLAY INVISIBLE (-2875 3850);
FORCEPROP 1 LAST PATH I49
J 0
(-2825 4000);
DISPLAY 0.978723 (-2825 4000);
PAINT WHITE (-2825 4000);
DISPLAY INVISIBLE (-2825 4000);
FORCEPROP 1 LAST PART_NUMBER CH5471MEB01
J 0
(-2825 3700);
DISPLAY 0.978723 (-2825 3700);
DISPLAY INVISIBLE (-2825 3700);
FORCEADD Q_RES..1
(-7550 4050);
FORCEPROP 1 LAST LOCATION R1045
J 0
(-7825 4075);
DISPLAY 0.808511 (-7825 4075);
FORCEPROP 2 LAST SEC 1
J 0
(-7600 4250);
DISPLAY 0.680851 (-7600 4250);
PAINT MONO (-7600 4250);
DISPLAY INVISIBLE (-7600 4250);
FORCEPROP 1 LASTPIN (-7650 4050) $PN 1
J 0
(-7638 4062);
DISPLAY 0.787234 (-7638 4062);
PAINT MONO (-7638 4062);
FORCEPROP 1 LASTPIN (-7450 4050) $PN 2
J 0
(-7488 4062);
DISPLAY 0.787234 (-7488 4062);
PAINT MONO (-7488 4062);
FORCEPROP 1 LAST VALUE 0
J 2
(-7400 4075);
DISPLAY 0.638298 (-7400 4075);
FORCEPROP 1 LAST PACK_TYPE 0402LF
J 0
(-7700 4000);
DISPLAY 0.638298 (-7700 4000);
FORCEPROP 1 LAST TOLERANCE 5%
J 0
(-7500 4000);
DISPLAY 0.638298 (-7500 4000);
FORCEPROP 1 LAST WATTAGE 1/16W
J 2
(-7550 3950);
DISPLAY 0.638298 (-7550 3950);
FORCEPROP 1 LAST MATERIAL EMPTY
J 0
(-7525 3950);
DISPLAY 0.638298 (-7525 3950);
FORCEPROP 2 LAST SEC_TYPE 0402LF
J 0
(-7600 4250);
DISPLAY 0.680851 (-7600 4250);
DISPLAY INVISIBLE (-7600 4250);
FORCEPROP 2 LAST CDS_LIB pure_quanta
J 0
(-7550 4050);
DISPLAY INVISIBLE (-7550 4050);
FORCEPROP 1 LAST PATH I5
J 0
(-7600 4200);
DISPLAY 0.978723 (-7600 4200);
PAINT WHITE (-7600 4200);
DISPLAY INVISIBLE (-7600 4200);
FORCEPROP 1 LAST PART_NUMBER CS00002JB13
J 0
(-7600 4150);
DISPLAY 0.978723 (-7600 4150);
DISPLAY INVISIBLE (-7600 4150);
FORCEADD Q_CAP..1
(-3100 4475);
FORCEPROP 1 LAST LOCATION C798
J 0
(-3050 4575);
DISPLAY 0.978723 (-3050 4575);
PAINT WHITE (-3050 4575);
FORCEPROP 0 LAST $SEC 1
J 0
(-3050 4625);
DISPLAY 0.680851 (-3050 4625);
PAINT MONO (-3050 4625);
DISPLAY INVISIBLE (-3050 4625);
FORCEPROP 0 LAST CDS_SEC 1
J 0
(-3050 4625);
DISPLAY 0.680851 (-3050 4625);
DISPLAY INVISIBLE (-3050 4625);
FORCEPROP 1 LASTPIN (-3100 4575) $PN 1
J 0
(-3090 4555);
DISPLAY 0.787234 (-3090 4555);
PAINT MONO (-3090 4555);
FORCEPROP 1 LASTPIN (-3100 4375) $PN 2
J 0
(-3090 4355);
DISPLAY 0.787234 (-3090 4355);
PAINT MONO (-3090 4355);
FORCEPROP 1 LAST TOLERANCE 20%
J 0
(-3050 4425);
DISPLAY 0.510638 (-3050 4425);
FORCEPROP 1 LAST PACK_TYPE C0805
J 0
(-3050 4325);
DISPLAY 0.510638 (-3050 4325);
FORCEPROP 1 LAST VOLTAGE 4V
J 0
(-3050 4475);
DISPLAY 0.510638 (-3050 4475);
FORCEPROP 1 LAST MATERIAL X6S
J 0
(-3050 4375);
DISPLAY 0.510638 (-3050 4375);
FORCEPROP 1 LAST VALUE 100UF
J 0
(-3050 4525);
DISPLAY 0.510638 (-3050 4525);
FORCEPROP 2 LAST CDS_LIB pure_quanta
J 0
(-3100 4475);
DISPLAY INVISIBLE (-3100 4475);
FORCEPROP 1 LAST PATH I50
J 0
(-3050 4625);
DISPLAY 0.978723 (-3050 4625);
PAINT WHITE (-3050 4625);
DISPLAY INVISIBLE (-3050 4625);
FORCEPROP 1 LAST PART_NUMBER CH710KMEA01
J 0
(-3050 4325);
DISPLAY 0.404255 (-3050 4325);
DISPLAY INVISIBLE (-3050 4325);
FORCEADD Q_CAP..1
(-2875 4475);
FORCEPROP 1 LAST LOCATION C802
J 0
(-2825 4575);
DISPLAY 0.978723 (-2825 4575);
PAINT WHITE (-2825 4575);
FORCEPROP 0 LAST $SEC 1
J 0
(-2825 4625);
DISPLAY 0.680851 (-2825 4625);
PAINT MONO (-2825 4625);
DISPLAY INVISIBLE (-2825 4625);
FORCEPROP 0 LAST CDS_SEC 1
J 0
(-2825 4625);
DISPLAY 0.680851 (-2825 4625);
DISPLAY INVISIBLE (-2825 4625);
FORCEPROP 1 LASTPIN (-2875 4575) $PN 1
J 0
(-2865 4555);
DISPLAY 0.787234 (-2865 4555);
PAINT MONO (-2865 4555);
FORCEPROP 1 LASTPIN (-2875 4375) $PN 2
J 0
(-2865 4355);
DISPLAY 0.787234 (-2865 4355);
PAINT MONO (-2865 4355);
FORCEPROP 1 LAST VALUE 100UF
J 0
(-2825 4525);
DISPLAY 0.510638 (-2825 4525);
FORCEPROP 1 LAST VOLTAGE 4V
J 0
(-2825 4475);
DISPLAY 0.510638 (-2825 4475);
FORCEPROP 1 LAST TOLERANCE 20%
J 0
(-2825 4425);
DISPLAY 0.510638 (-2825 4425);
FORCEPROP 1 LAST MATERIAL X6S
J 0
(-2825 4375);
DISPLAY 0.510638 (-2825 4375);
FORCEPROP 1 LAST PACK_TYPE C0805
J 0
(-2825 4325);
DISPLAY 0.510638 (-2825 4325);
FORCEPROP 2 LAST CDS_LIB pure_quanta
J 0
(-2875 4475);
DISPLAY INVISIBLE (-2875 4475);
FORCEPROP 1 LAST PATH I51
J 0
(-2825 4625);
DISPLAY 0.978723 (-2825 4625);
PAINT WHITE (-2825 4625);
DISPLAY INVISIBLE (-2825 4625);
FORCEPROP 1 LAST PART_NUMBER CH710KMEA01
J 0
(-2825 4325);
DISPLAY 0.404255 (-2825 4325);
DISPLAY INVISIBLE (-2825 4325);
FORCEADD Q_CAP..1
(-2625 3225);
FORCEPROP 1 LAST LOCATION C792
J 0
(-2575 3325);
DISPLAY 0.978723 (-2575 3325);
PAINT WHITE (-2575 3325);
FORCEPROP 0 LAST $SEC 1
J 0
(-2575 3375);
DISPLAY 0.680851 (-2575 3375);
PAINT MONO (-2575 3375);
DISPLAY INVISIBLE (-2575 3375);
FORCEPROP 0 LAST CDS_SEC 1
J 0
(-2575 3375);
DISPLAY 0.680851 (-2575 3375);
DISPLAY INVISIBLE (-2575 3375);
FORCEPROP 1 LASTPIN (-2625 3325) $PN 1
J 0
(-2615 3305);
DISPLAY 0.787234 (-2615 3305);
PAINT MONO (-2615 3305);
FORCEPROP 1 LASTPIN (-2625 3125) $PN 2
J 0
(-2615 3105);
DISPLAY 0.787234 (-2615 3105);
PAINT MONO (-2615 3105);
FORCEPROP 1 LAST VOLTAGE 4V
J 0
(-2575 3225);
DISPLAY 0.510638 (-2575 3225);
FORCEPROP 1 LAST MATERIAL X6S
J 0
(-2575 3125);
DISPLAY 0.510638 (-2575 3125);
FORCEPROP 1 LAST VALUE 1UF
J 0
(-2575 3275);
DISPLAY 0.510638 (-2575 3275);
FORCEPROP 1 LAST TOLERANCE 20%
J 0
(-2575 3175);
DISPLAY 0.510638 (-2575 3175);
FORCEPROP 1 LAST PACK_TYPE 0201
J 0
(-2575 3075);
DISPLAY 0.510638 (-2575 3075);
FORCEPROP 2 LAST CDS_LIB pure_quanta
J 0
(-2625 3225);
DISPLAY INVISIBLE (-2625 3225);
FORCEPROP 1 LAST PATH I52
J 0
(-2575 3375);
DISPLAY 0.978723 (-2575 3375);
PAINT WHITE (-2575 3375);
DISPLAY INVISIBLE (-2575 3375);
FORCEPROP 1 LAST PART_NUMBER CH-10KMEE00
J 0
(-2575 3075);
DISPLAY 0.510638 (-2575 3075);
DISPLAY INVISIBLE (-2575 3075);
FORCEADD Q_CAP..1
(-2375 3200);
FORCEPROP 1 LAST LOCATION C975
J 0
(-2325 3300);
DISPLAY 0.978723 (-2325 3300);
PAINT WHITE (-2325 3300);
FORCEPROP 0 LAST $SEC 1
J 0
(-2325 3350);
DISPLAY 0.680851 (-2325 3350);
PAINT MONO (-2325 3350);
DISPLAY INVISIBLE (-2325 3350);
FORCEPROP 0 LAST CDS_SEC 1
J 0
(-2325 3350);
DISPLAY 0.680851 (-2325 3350);
DISPLAY INVISIBLE (-2325 3350);
FORCEPROP 1 LASTPIN (-2375 3300) $PN 1
J 0
(-2365 3280);
DISPLAY 0.787234 (-2365 3280);
PAINT MONO (-2365 3280);
FORCEPROP 1 LASTPIN (-2375 3100) $PN 2
J 0
(-2365 3080);
DISPLAY 0.787234 (-2365 3080);
PAINT MONO (-2365 3080);
FORCEPROP 1 LAST PACK_TYPE 0201
J 0
(-2325 3050);
DISPLAY 0.510638 (-2325 3050);
FORCEPROP 1 LAST MATERIAL X6S
J 0
(-2325 3100);
DISPLAY 0.510638 (-2325 3100);
FORCEPROP 1 LAST VALUE 1UF
J 0
(-2325 3250);
DISPLAY 0.510638 (-2325 3250);
FORCEPROP 1 LAST VOLTAGE 4V
J 0
(-2325 3200);
DISPLAY 0.510638 (-2325 3200);
FORCEPROP 1 LAST TOLERANCE 20%
J 0
(-2325 3150);
DISPLAY 0.510638 (-2325 3150);
FORCEPROP 2 LAST CDS_LIB pure_quanta
J 0
(-2375 3200);
DISPLAY INVISIBLE (-2375 3200);
FORCEPROP 1 LAST PATH I54
J 0
(-2325 3350);
DISPLAY 0.978723 (-2325 3350);
PAINT WHITE (-2325 3350);
DISPLAY INVISIBLE (-2325 3350);
FORCEPROP 1 LAST PART_NUMBER CH-10KMEE00
J 0
(-2325 3050);
DISPLAY 0.510638 (-2325 3050);
DISPLAY INVISIBLE (-2325 3050);
FORCEADD Q_CAP..1
(-2100 3200);
FORCEPROP 1 LAST LOCATION C979
J 0
(-2050 3300);
DISPLAY 0.978723 (-2050 3300);
PAINT WHITE (-2050 3300);
FORCEPROP 0 LAST $SEC 1
J 0
(-2050 3350);
DISPLAY 0.680851 (-2050 3350);
PAINT MONO (-2050 3350);
DISPLAY INVISIBLE (-2050 3350);
FORCEPROP 0 LAST CDS_SEC 1
J 0
(-2050 3350);
DISPLAY 0.680851 (-2050 3350);
DISPLAY INVISIBLE (-2050 3350);
FORCEPROP 1 LASTPIN (-2100 3300) $PN 1
J 0
(-2090 3280);
DISPLAY 0.787234 (-2090 3280);
PAINT MONO (-2090 3280);
FORCEPROP 1 LASTPIN (-2100 3100) $PN 2
J 0
(-2090 3080);
DISPLAY 0.787234 (-2090 3080);
PAINT MONO (-2090 3080);
FORCEPROP 1 LAST VALUE 1UF
J 0
(-2050 3250);
DISPLAY 0.510638 (-2050 3250);
FORCEPROP 1 LAST TOLERANCE 20%
J 0
(-2050 3150);
DISPLAY 0.510638 (-2050 3150);
FORCEPROP 1 LAST MATERIAL X6S
J 0
(-2050 3100);
DISPLAY 0.510638 (-2050 3100);
FORCEPROP 1 LAST PACK_TYPE 0201
J 0
(-2050 3050);
DISPLAY 0.510638 (-2050 3050);
FORCEPROP 1 LAST VOLTAGE 4V
J 0
(-2050 3200);
DISPLAY 0.510638 (-2050 3200);
FORCEPROP 2 LAST CDS_LIB pure_quanta
J 0
(-2100 3200);
DISPLAY INVISIBLE (-2100 3200);
FORCEPROP 1 LAST PATH I55
J 0
(-2050 3350);
DISPLAY 0.978723 (-2050 3350);
PAINT WHITE (-2050 3350);
DISPLAY INVISIBLE (-2050 3350);
FORCEPROP 1 LAST PART_NUMBER CH-10KMEE00
J 0
(-2050 3050);
DISPLAY 0.510638 (-2050 3050);
DISPLAY INVISIBLE (-2050 3050);
FORCEADD Q_CAP..1
(-2650 3850);
FORCEPROP 1 LAST LOCATION C967
J 0
(-2600 3950);
DISPLAY 0.978723 (-2600 3950);
PAINT WHITE (-2600 3950);
FORCEPROP 0 LAST $SEC 1
J 0
(-2600 4000);
DISPLAY 0.680851 (-2600 4000);
PAINT MONO (-2600 4000);
DISPLAY INVISIBLE (-2600 4000);
FORCEPROP 0 LAST CDS_SEC 1
J 0
(-2600 4000);
DISPLAY 0.680851 (-2600 4000);
DISPLAY INVISIBLE (-2600 4000);
FORCEPROP 1 LASTPIN (-2650 3950) $PN 1
J 0
(-2640 3930);
DISPLAY 0.787234 (-2640 3930);
PAINT MONO (-2640 3930);
FORCEPROP 1 LASTPIN (-2650 3750) $PN 2
J 0
(-2640 3730);
DISPLAY 0.787234 (-2640 3730);
PAINT MONO (-2640 3730);
FORCEPROP 1 LAST VALUE 4.7UF
J 0
(-2600 3900);
DISPLAY 0.510638 (-2600 3900);
FORCEPROP 1 LAST MATERIAL X6S
J 0
(-2600 3750);
DISPLAY 0.510638 (-2600 3750);
FORCEPROP 1 LAST PACK_TYPE 0402
J 0
(-2600 3700);
DISPLAY 0.510638 (-2600 3700);
FORCEPROP 1 LAST TOLERANCE 20%
J 0
(-2600 3800);
DISPLAY 0.510638 (-2600 3800);
FORCEPROP 1 LAST VOLTAGE 6.3V
J 0
(-2600 3850);
DISPLAY 0.510638 (-2600 3850);
FORCEPROP 2 LAST CDS_LIB pure_quanta
J 0
(-2650 3850);
DISPLAY INVISIBLE (-2650 3850);
FORCEPROP 1 LAST PATH I56
J 0
(-2600 4000);
DISPLAY 0.978723 (-2600 4000);
PAINT WHITE (-2600 4000);
DISPLAY INVISIBLE (-2600 4000);
FORCEPROP 1 LAST PART_NUMBER CH5471MEB01
J 0
(-2600 3700);
DISPLAY 0.978723 (-2600 3700);
DISPLAY INVISIBLE (-2600 3700);
FORCEADD Q_CAP..1
(-2400 3850);
FORCEPROP 1 LAST LOCATION C970
J 0
(-2350 3950);
DISPLAY 0.978723 (-2350 3950);
PAINT WHITE (-2350 3950);
FORCEPROP 0 LAST $SEC 1
J 0
(-2350 4000);
DISPLAY 0.680851 (-2350 4000);
PAINT MONO (-2350 4000);
DISPLAY INVISIBLE (-2350 4000);
FORCEPROP 0 LAST CDS_SEC 1
J 0
(-2350 4000);
DISPLAY 0.680851 (-2350 4000);
DISPLAY INVISIBLE (-2350 4000);
FORCEPROP 1 LASTPIN (-2400 3950) $PN 1
J 0
(-2390 3930);
DISPLAY 0.787234 (-2390 3930);
PAINT MONO (-2390 3930);
FORCEPROP 1 LASTPIN (-2400 3750) $PN 2
J 0
(-2390 3730);
DISPLAY 0.787234 (-2390 3730);
PAINT MONO (-2390 3730);
FORCEPROP 1 LAST MATERIAL X6S
J 0
(-2350 3750);
DISPLAY 0.510638 (-2350 3750);
FORCEPROP 1 LAST TOLERANCE 20%
J 0
(-2350 3800);
DISPLAY 0.510638 (-2350 3800);
FORCEPROP 1 LAST VOLTAGE 6.3V
J 0
(-2350 3850);
DISPLAY 0.510638 (-2350 3850);
FORCEPROP 1 LAST PACK_TYPE 0402
J 0
(-2350 3700);
DISPLAY 0.510638 (-2350 3700);
FORCEPROP 1 LAST VALUE 4.7UF
J 0
(-2350 3900);
DISPLAY 0.510638 (-2350 3900);
FORCEPROP 2 LAST CDS_LIB pure_quanta
J 0
(-2400 3850);
DISPLAY INVISIBLE (-2400 3850);
FORCEPROP 1 LAST PATH I57
J 0
(-2350 4000);
DISPLAY 0.978723 (-2350 4000);
PAINT WHITE (-2350 4000);
DISPLAY INVISIBLE (-2350 4000);
FORCEPROP 1 LAST PART_NUMBER CH5471MEB01
J 0
(-2350 3700);
DISPLAY 0.978723 (-2350 3700);
DISPLAY INVISIBLE (-2350 3700);
FORCEADD Q_CAP..1
(-2650 4475);
FORCEPROP 1 LAST LOCATION C966
J 0
(-2600 4575);
DISPLAY 0.978723 (-2600 4575);
PAINT WHITE (-2600 4575);
FORCEPROP 0 LAST $SEC 1
J 0
(-2600 4625);
DISPLAY 0.680851 (-2600 4625);
PAINT MONO (-2600 4625);
DISPLAY INVISIBLE (-2600 4625);
FORCEPROP 0 LAST CDS_SEC 1
J 0
(-2600 4625);
DISPLAY 0.680851 (-2600 4625);
DISPLAY INVISIBLE (-2600 4625);
FORCEPROP 1 LASTPIN (-2650 4575) $PN 1
J 0
(-2640 4555);
DISPLAY 0.787234 (-2640 4555);
PAINT MONO (-2640 4555);
FORCEPROP 1 LASTPIN (-2650 4375) $PN 2
J 0
(-2640 4355);
DISPLAY 0.787234 (-2640 4355);
PAINT MONO (-2640 4355);
FORCEPROP 1 LAST PACK_TYPE C0805
J 0
(-2600 4325);
DISPLAY 0.510638 (-2600 4325);
FORCEPROP 1 LAST TOLERANCE 20%
J 0
(-2600 4425);
DISPLAY 0.510638 (-2600 4425);
FORCEPROP 1 LAST VALUE 100UF
J 0
(-2600 4525);
DISPLAY 0.510638 (-2600 4525);
FORCEPROP 1 LAST MATERIAL X6S
J 0
(-2600 4375);
DISPLAY 0.510638 (-2600 4375);
FORCEPROP 1 LAST VOLTAGE 4V
J 0
(-2600 4475);
DISPLAY 0.510638 (-2600 4475);
FORCEPROP 2 LAST CDS_LIB pure_quanta
J 0
(-2650 4475);
DISPLAY INVISIBLE (-2650 4475);
FORCEPROP 1 LAST PATH I58
J 0
(-2600 4625);
DISPLAY 0.978723 (-2600 4625);
PAINT WHITE (-2600 4625);
DISPLAY INVISIBLE (-2600 4625);
FORCEPROP 1 LAST PART_NUMBER CH710KMEA01
J 0
(-2600 4325);
DISPLAY 0.404255 (-2600 4325);
DISPLAY INVISIBLE (-2600 4325);
FORCEADD Q_CAP..1
(-2400 4475);
FORCEPROP 1 LAST LOCATION C969
J 0
(-2350 4575);
DISPLAY 0.978723 (-2350 4575);
PAINT WHITE (-2350 4575);
FORCEPROP 0 LAST $SEC 1
J 0
(-2350 4625);
DISPLAY 0.680851 (-2350 4625);
PAINT MONO (-2350 4625);
DISPLAY INVISIBLE (-2350 4625);
FORCEPROP 0 LAST CDS_SEC 1
J 0
(-2350 4625);
DISPLAY 0.680851 (-2350 4625);
DISPLAY INVISIBLE (-2350 4625);
FORCEPROP 1 LASTPIN (-2400 4575) $PN 1
J 0
(-2390 4555);
DISPLAY 0.787234 (-2390 4555);
PAINT MONO (-2390 4555);
FORCEPROP 1 LASTPIN (-2400 4375) $PN 2
J 0
(-2390 4355);
DISPLAY 0.787234 (-2390 4355);
PAINT MONO (-2390 4355);
FORCEPROP 1 LAST VOLTAGE 4V
J 0
(-2350 4475);
DISPLAY 0.510638 (-2350 4475);
FORCEPROP 1 LAST PACK_TYPE C0402
J 0
(-2350 4325);
DISPLAY 0.510638 (-2350 4325);
FORCEPROP 1 LAST TOLERANCE 20%
J 0
(-2350 4425);
DISPLAY 0.510638 (-2350 4425);
FORCEPROP 1 LAST MATERIAL X6S
J 0
(-2350 4375);
DISPLAY 0.510638 (-2350 4375);
FORCEPROP 1 LAST VALUE 22UF
J 0
(-2350 4525);
DISPLAY 0.510638 (-2350 4525);
FORCEPROP 2 LAST CDS_LIB pure_quanta
J 0
(-2400 4475);
DISPLAY INVISIBLE (-2400 4475);
FORCEPROP 1 LAST PATH I59
J 0
(-2350 4625);
DISPLAY 0.978723 (-2350 4625);
PAINT WHITE (-2350 4625);
DISPLAY INVISIBLE (-2350 4625);
FORCEPROP 1 LAST PART_NUMBER CH622KMEB02
J 0
(-2350 4325);
DISPLAY 0.978723 (-2350 4325);
DISPLAY INVISIBLE (-2350 4325);
FORCEADD Q_CAP..1
(-7050 4475);
FORCEPROP 1 LAST LOCATION C666
J 0
(-7000 4575);
DISPLAY 0.638298 (-7000 4575);
PAINT WHITE (-7000 4575);
FORCEPROP 0 LAST $SEC 1
J 0
(-7000 4600);
DISPLAY 0.680851 (-7000 4600);
PAINT MONO (-7000 4600);
DISPLAY INVISIBLE (-7000 4600);
FORCEPROP 0 LAST CDS_SEC 1
J 0
(-7000 4600);
DISPLAY 0.680851 (-7000 4600);
DISPLAY INVISIBLE (-7000 4600);
FORCEPROP 1 LASTPIN (-7050 4575) $PN 1
J 0
(-7040 4555);
DISPLAY 0.787234 (-7040 4555);
PAINT MONO (-7040 4555);
FORCEPROP 1 LASTPIN (-7050 4375) $PN 2
J 0
(-7040 4355);
DISPLAY 0.787234 (-7040 4355);
PAINT MONO (-7040 4355);
FORCEPROP 1 LAST TOLERANCE 20%
J 0
(-7000 4425);
DISPLAY 0.510638 (-7000 4425);
FORCEPROP 1 LAST MATERIAL X6S
J 0
(-7000 4375);
DISPLAY 0.510638 (-7000 4375);
FORCEPROP 1 LAST PACK_TYPE C0805
J 0
(-7000 4325);
DISPLAY 0.510638 (-7000 4325);
FORCEPROP 1 LAST VALUE 100UF
J 0
(-7000 4525);
DISPLAY 0.510638 (-7000 4525);
FORCEPROP 1 LAST VOLTAGE 4V
J 0
(-7000 4475);
DISPLAY 0.510638 (-7000 4475);
FORCEPROP 2 LAST CDS_LIB pure_quanta
J 0
(-7050 4475);
DISPLAY INVISIBLE (-7050 4475);
FORCEPROP 1 LAST PATH I6
J 0
(-7000 4625);
DISPLAY 0.978723 (-7000 4625);
PAINT WHITE (-7000 4625);
DISPLAY INVISIBLE (-7000 4625);
FORCEPROP 1 LAST PART_NUMBER CH710KMEA01
J 0
(-7000 4325);
DISPLAY 0.404255 (-7000 4325);
DISPLAY INVISIBLE (-7000 4325);
FORCEADD Q_CAP..1
(-2175 3850);
FORCEPROP 1 LAST LOCATION C977
J 0
(-2125 3950);
DISPLAY 0.978723 (-2125 3950);
PAINT WHITE (-2125 3950);
FORCEPROP 0 LAST $SEC 1
J 0
(-2125 4000);
DISPLAY 0.680851 (-2125 4000);
PAINT MONO (-2125 4000);
DISPLAY INVISIBLE (-2125 4000);
FORCEPROP 0 LAST CDS_SEC 1
J 0
(-2125 4000);
DISPLAY 0.680851 (-2125 4000);
DISPLAY INVISIBLE (-2125 4000);
FORCEPROP 1 LASTPIN (-2175 3950) $PN 1
J 0
(-2165 3930);
DISPLAY 0.787234 (-2165 3930);
PAINT MONO (-2165 3930);
FORCEPROP 1 LASTPIN (-2175 3750) $PN 2
J 0
(-2165 3730);
DISPLAY 0.787234 (-2165 3730);
PAINT MONO (-2165 3730);
FORCEPROP 1 LAST VALUE 4.7UF
J 0
(-2125 3900);
DISPLAY 0.510638 (-2125 3900);
FORCEPROP 1 LAST VOLTAGE 6.3V
J 0
(-2125 3850);
DISPLAY 0.510638 (-2125 3850);
FORCEPROP 1 LAST TOLERANCE 20%
J 0
(-2125 3800);
DISPLAY 0.510638 (-2125 3800);
FORCEPROP 1 LAST MATERIAL X6S
J 0
(-2125 3750);
DISPLAY 0.510638 (-2125 3750);
FORCEPROP 1 LAST PACK_TYPE 0402
J 0
(-2125 3700);
DISPLAY 0.510638 (-2125 3700);
FORCEPROP 2 LAST CDS_LIB pure_quanta
J 0
(-2175 3850);
DISPLAY INVISIBLE (-2175 3850);
FORCEPROP 1 LAST PATH I60
J 0
(-2125 4000);
DISPLAY 0.978723 (-2125 4000);
PAINT WHITE (-2125 4000);
DISPLAY INVISIBLE (-2125 4000);
FORCEPROP 1 LAST PART_NUMBER CH5471MEB01
J 0
(-2125 3700);
DISPLAY 0.978723 (-2125 3700);
DISPLAY INVISIBLE (-2125 3700);
FORCEADD Q_CAP..1
(-1950 3850);
FORCEPROP 1 LAST LOCATION C978
J 0
(-1900 3950);
DISPLAY 0.978723 (-1900 3950);
PAINT WHITE (-1900 3950);
FORCEPROP 0 LAST $SEC 1
J 0
(-1900 4000);
DISPLAY 0.680851 (-1900 4000);
PAINT MONO (-1900 4000);
DISPLAY INVISIBLE (-1900 4000);
FORCEPROP 0 LAST CDS_SEC 1
J 0
(-1900 4000);
DISPLAY 0.680851 (-1900 4000);
DISPLAY INVISIBLE (-1900 4000);
FORCEPROP 1 LASTPIN (-1950 3950) $PN 1
J 0
(-1940 3930);
DISPLAY 0.787234 (-1940 3930);
PAINT MONO (-1940 3930);
FORCEPROP 1 LASTPIN (-1950 3750) $PN 2
J 0
(-1940 3730);
DISPLAY 0.787234 (-1940 3730);
PAINT MONO (-1940 3730);
FORCEPROP 1 LAST VOLTAGE 4V
J 0
(-1900 3850);
DISPLAY 0.510638 (-1900 3850);
FORCEPROP 1 LAST VALUE 1UF
J 0
(-1900 3900);
DISPLAY 0.510638 (-1900 3900);
FORCEPROP 1 LAST MATERIAL X6S
J 0
(-1900 3750);
DISPLAY 0.510638 (-1900 3750);
FORCEPROP 1 LAST TOLERANCE 20%
J 0
(-1900 3800);
DISPLAY 0.510638 (-1900 3800);
FORCEPROP 1 LAST PACK_TYPE 0201
J 0
(-1900 3700);
DISPLAY 0.510638 (-1900 3700);
FORCEPROP 2 LAST CDS_LIB pure_quanta
J 0
(-1950 3850);
DISPLAY INVISIBLE (-1950 3850);
FORCEPROP 1 LAST PATH I61
J 0
(-1900 4000);
DISPLAY 0.978723 (-1900 4000);
PAINT WHITE (-1900 4000);
DISPLAY INVISIBLE (-1900 4000);
FORCEPROP 1 LAST PART_NUMBER CH-10KMEE00
J 0
(-1900 3700);
DISPLAY 0.510638 (-1900 3700);
DISPLAY INVISIBLE (-1900 3700);
FORCEADD Q_CAP..1
(-1725 3850);
FORCEPROP 1 LAST LOCATION C783
J 0
(-1675 3950);
DISPLAY 0.978723 (-1675 3950);
PAINT WHITE (-1675 3950);
FORCEPROP 0 LAST $SEC 1
J 0
(-1675 4000);
DISPLAY 0.680851 (-1675 4000);
PAINT MONO (-1675 4000);
DISPLAY INVISIBLE (-1675 4000);
FORCEPROP 0 LAST CDS_SEC 1
J 0
(-1675 4000);
DISPLAY 0.680851 (-1675 4000);
DISPLAY INVISIBLE (-1675 4000);
FORCEPROP 1 LASTPIN (-1725 3950) $PN 1
J 0
(-1715 3930);
DISPLAY 0.787234 (-1715 3930);
PAINT MONO (-1715 3930);
FORCEPROP 1 LASTPIN (-1725 3750) $PN 2
J 0
(-1715 3730);
DISPLAY 0.787234 (-1715 3730);
PAINT MONO (-1715 3730);
FORCEPROP 1 LAST PACK_TYPE 0201
J 0
(-1675 3700);
DISPLAY 0.510638 (-1675 3700);
FORCEPROP 1 LAST TOLERANCE 20%
J 0
(-1675 3800);
DISPLAY 0.510638 (-1675 3800);
FORCEPROP 1 LAST MATERIAL X6S
J 0
(-1675 3750);
DISPLAY 0.510638 (-1675 3750);
FORCEPROP 1 LAST VOLTAGE 4V
J 0
(-1675 3850);
DISPLAY 0.510638 (-1675 3850);
FORCEPROP 1 LAST VALUE 1UF
J 0
(-1675 3900);
DISPLAY 0.510638 (-1675 3900);
FORCEPROP 2 LAST CDS_LIB pure_quanta
J 0
(-1725 3850);
DISPLAY INVISIBLE (-1725 3850);
FORCEPROP 1 LAST PATH I62
J 0
(-1675 4000);
DISPLAY 0.978723 (-1675 4000);
PAINT WHITE (-1675 4000);
DISPLAY INVISIBLE (-1675 4000);
FORCEPROP 1 LAST PART_NUMBER CH-10KMEE00
J 0
(-1675 3700);
DISPLAY 0.510638 (-1675 3700);
DISPLAY INVISIBLE (-1675 3700);
FORCEADD Q_CAP..1
(-2175 4475);
FORCEPROP 1 LAST LOCATION C988
J 0
(-2125 4575);
DISPLAY 0.978723 (-2125 4575);
PAINT WHITE (-2125 4575);
FORCEPROP 0 LAST $SEC 1
J 0
(-2125 4625);
DISPLAY 0.680851 (-2125 4625);
PAINT MONO (-2125 4625);
DISPLAY INVISIBLE (-2125 4625);
FORCEPROP 0 LAST CDS_SEC 1
J 0
(-2125 4625);
DISPLAY 0.680851 (-2125 4625);
DISPLAY INVISIBLE (-2125 4625);
FORCEPROP 1 LASTPIN (-2175 4575) $PN 1
J 0
(-2165 4555);
DISPLAY 0.787234 (-2165 4555);
PAINT MONO (-2165 4555);
FORCEPROP 1 LASTPIN (-2175 4375) $PN 2
J 0
(-2165 4355);
DISPLAY 0.787234 (-2165 4355);
PAINT MONO (-2165 4355);
FORCEPROP 1 LAST VALUE 22UF
J 0
(-2125 4525);
DISPLAY 0.510638 (-2125 4525);
FORCEPROP 1 LAST VOLTAGE 4V
J 0
(-2125 4475);
DISPLAY 0.510638 (-2125 4475);
FORCEPROP 1 LAST TOLERANCE 20%
J 0
(-2125 4425);
DISPLAY 0.510638 (-2125 4425);
FORCEPROP 1 LAST MATERIAL X6S
J 0
(-2125 4375);
DISPLAY 0.510638 (-2125 4375);
FORCEPROP 1 LAST PACK_TYPE C0402
J 0
(-2125 4325);
DISPLAY 0.510638 (-2125 4325);
FORCEPROP 2 LAST CDS_LIB pure_quanta
J 0
(-2175 4475);
DISPLAY INVISIBLE (-2175 4475);
FORCEPROP 1 LAST PATH I63
J 0
(-2125 4625);
DISPLAY 0.978723 (-2125 4625);
PAINT WHITE (-2125 4625);
DISPLAY INVISIBLE (-2125 4625);
FORCEPROP 1 LAST PART_NUMBER CH622KMEB02
J 0
(-2125 4325);
DISPLAY 0.978723 (-2125 4325);
DISPLAY INVISIBLE (-2125 4325);
FORCEADD Q_CAP..1
(-1950 4475);
FORCEPROP 1 LAST LOCATION C974
J 0
(-1900 4575);
DISPLAY 0.978723 (-1900 4575);
PAINT WHITE (-1900 4575);
FORCEPROP 0 LAST $SEC 1
J 0
(-1900 4625);
DISPLAY 0.680851 (-1900 4625);
PAINT MONO (-1900 4625);
DISPLAY INVISIBLE (-1900 4625);
FORCEPROP 0 LAST CDS_SEC 1
J 0
(-1900 4625);
DISPLAY 0.680851 (-1900 4625);
DISPLAY INVISIBLE (-1900 4625);
FORCEPROP 1 LASTPIN (-1950 4575) $PN 1
J 0
(-1940 4555);
DISPLAY 0.787234 (-1940 4555);
PAINT MONO (-1940 4555);
FORCEPROP 1 LASTPIN (-1950 4375) $PN 2
J 0
(-1940 4355);
DISPLAY 0.787234 (-1940 4355);
PAINT MONO (-1940 4355);
FORCEPROP 1 LAST VALUE 22UF
J 0
(-1900 4525);
DISPLAY 0.510638 (-1900 4525);
FORCEPROP 1 LAST VOLTAGE 4V
J 0
(-1900 4475);
DISPLAY 0.510638 (-1900 4475);
FORCEPROP 1 LAST TOLERANCE 20%
J 0
(-1900 4425);
DISPLAY 0.510638 (-1900 4425);
FORCEPROP 1 LAST PACK_TYPE C0402
J 0
(-1900 4325);
DISPLAY 0.510638 (-1900 4325);
FORCEPROP 1 LAST MATERIAL X6S
J 0
(-1900 4375);
DISPLAY 0.510638 (-1900 4375);
FORCEPROP 2 LAST CDS_LIB pure_quanta
J 0
(-1950 4475);
DISPLAY INVISIBLE (-1950 4475);
FORCEPROP 1 LAST PATH I64
J 0
(-1900 4625);
DISPLAY 0.978723 (-1900 4625);
PAINT WHITE (-1900 4625);
DISPLAY INVISIBLE (-1900 4625);
FORCEPROP 1 LAST PART_NUMBER CH622KMEB02
J 0
(-1900 4325);
DISPLAY 0.978723 (-1900 4325);
DISPLAY INVISIBLE (-1900 4325);
FORCEADD Q_CAP..1
(-1725 4475);
FORCEPROP 1 LAST LOCATION C799
J 0
(-1675 4575);
DISPLAY 0.978723 (-1675 4575);
PAINT WHITE (-1675 4575);
FORCEPROP 0 LAST $SEC 1
J 0
(-1675 4625);
DISPLAY 0.680851 (-1675 4625);
PAINT MONO (-1675 4625);
DISPLAY INVISIBLE (-1675 4625);
FORCEPROP 0 LAST CDS_SEC 1
J 0
(-1675 4625);
DISPLAY 0.680851 (-1675 4625);
DISPLAY INVISIBLE (-1675 4625);
FORCEPROP 1 LASTPIN (-1725 4575) $PN 1
J 0
(-1715 4555);
DISPLAY 0.787234 (-1715 4555);
PAINT MONO (-1715 4555);
FORCEPROP 1 LASTPIN (-1725 4375) $PN 2
J 0
(-1715 4355);
DISPLAY 0.787234 (-1715 4355);
PAINT MONO (-1715 4355);
FORCEPROP 1 LAST MATERIAL X6S
J 0
(-1675 4375);
DISPLAY 0.510638 (-1675 4375);
FORCEPROP 1 LAST PACK_TYPE C0402
J 0
(-1675 4325);
DISPLAY 0.510638 (-1675 4325);
FORCEPROP 1 LAST VOLTAGE 4V
J 0
(-1675 4475);
DISPLAY 0.510638 (-1675 4475);
FORCEPROP 1 LAST VALUE 22UF
J 0
(-1675 4525);
DISPLAY 0.510638 (-1675 4525);
FORCEPROP 1 LAST TOLERANCE 20%
J 0
(-1675 4425);
DISPLAY 0.510638 (-1675 4425);
FORCEPROP 2 LAST CDS_LIB pure_quanta
J 0
(-1725 4475);
DISPLAY INVISIBLE (-1725 4475);
FORCEPROP 1 LAST PATH I65
J 0
(-1675 4625);
DISPLAY 0.978723 (-1675 4625);
PAINT WHITE (-1675 4625);
DISPLAY INVISIBLE (-1675 4625);
FORCEPROP 1 LAST PART_NUMBER CH622KMEB02
J 0
(-1675 4325);
DISPLAY 0.978723 (-1675 4325);
DISPLAY INVISIBLE (-1675 4325);
FORCEADD Q_CAP..1
(-1825 3200);
FORCEPROP 1 LAST LOCATION C983
J 0
(-1775 3300);
DISPLAY 0.978723 (-1775 3300);
PAINT WHITE (-1775 3300);
FORCEPROP 0 LAST $SEC 1
J 0
(-1775 3350);
DISPLAY 0.680851 (-1775 3350);
PAINT MONO (-1775 3350);
DISPLAY INVISIBLE (-1775 3350);
FORCEPROP 0 LAST CDS_SEC 1
J 0
(-1775 3350);
DISPLAY 0.680851 (-1775 3350);
DISPLAY INVISIBLE (-1775 3350);
FORCEPROP 1 LASTPIN (-1825 3300) $PN 1
J 0
(-1815 3280);
DISPLAY 0.787234 (-1815 3280);
PAINT MONO (-1815 3280);
FORCEPROP 1 LASTPIN (-1825 3100) $PN 2
J 0
(-1815 3080);
DISPLAY 0.787234 (-1815 3080);
PAINT MONO (-1815 3080);
FORCEPROP 1 LAST VOLTAGE 4V
J 0
(-1775 3200);
DISPLAY 0.510638 (-1775 3200);
FORCEPROP 1 LAST TOLERANCE 20%
J 0
(-1775 3150);
DISPLAY 0.510638 (-1775 3150);
FORCEPROP 1 LAST PACK_TYPE 0201
J 0
(-1775 3050);
DISPLAY 0.510638 (-1775 3050);
FORCEPROP 1 LAST MATERIAL X6S
J 0
(-1775 3100);
DISPLAY 0.510638 (-1775 3100);
FORCEPROP 1 LAST VALUE 1UF
J 0
(-1775 3250);
DISPLAY 0.510638 (-1775 3250);
FORCEPROP 2 LAST CDS_LIB pure_quanta
J 0
(-1825 3200);
DISPLAY INVISIBLE (-1825 3200);
FORCEPROP 1 LAST PATH I66
J 0
(-1775 3350);
DISPLAY 0.978723 (-1775 3350);
PAINT WHITE (-1775 3350);
DISPLAY INVISIBLE (-1775 3350);
FORCEPROP 1 LAST PART_NUMBER CH-10KMEE00
J 0
(-1775 3050);
DISPLAY 0.510638 (-1775 3050);
DISPLAY INVISIBLE (-1775 3050);
FORCEADD UNIVERSAL_GND..1
(-1225 2100);
FORCEPROP 3 LASTPIN (-1225 2150) SIG_NAME GND\g
J 0
(-1215 2160);
DISPLAY 0.659574 (-1215 2160);
PAINT MONO (-1215 2160);
DISPLAY INVISIBLE (-1215 2160);
FORCEPROP 2 LAST CDS_LIB pure_quanta_power
J 0
(-1225 2100);
DISPLAY INVISIBLE (-1225 2100);
FORCEPROP 1 LAST HDL_POWER GND
J 1
(-1200 2025);
DISPLAY 0.872340 (-1200 2025);
PAINT GREEN (-1200 2025);
DISPLAY INVISIBLE (-1200 2025);
FORCEPROP 1 LAST PATH I67
J 0
(-1150 2100);
DISPLAY 0.872340 (-1150 2100);
PAINT AQUA (-1150 2100);
DISPLAY INVISIBLE (-1150 2100);
FORCEADD Q_CAP..1
(-1475 2525);
FORCEPROP 1 LAST LOCATION C804
J 0
(-1425 2625);
DISPLAY 0.978723 (-1425 2625);
PAINT WHITE (-1425 2625);
FORCEPROP 0 LAST $SEC 1
J 0
(-1425 2675);
DISPLAY 0.680851 (-1425 2675);
PAINT MONO (-1425 2675);
DISPLAY INVISIBLE (-1425 2675);
FORCEPROP 0 LAST CDS_SEC 1
J 0
(-1425 2675);
DISPLAY 0.680851 (-1425 2675);
DISPLAY INVISIBLE (-1425 2675);
FORCEPROP 1 LASTPIN (-1475 2625) $PN 1
J 0
(-1465 2605);
DISPLAY 0.787234 (-1465 2605);
PAINT MONO (-1465 2605);
FORCEPROP 1 LASTPIN (-1475 2425) $PN 2
J 0
(-1465 2405);
DISPLAY 0.787234 (-1465 2405);
PAINT MONO (-1465 2405);
FORCEPROP 1 LAST PACK_TYPE C0201
J 0
(-1425 2375);
DISPLAY 0.638298 (-1425 2375);
FORCEPROP 1 LAST MATERIAL X7S
J 0
(-1425 2425);
DISPLAY 0.638298 (-1425 2425);
FORCEPROP 1 LAST VOLTAGE 10V
J 0
(-1425 2525);
DISPLAY 0.638298 (-1425 2525);
FORCEPROP 1 LAST TOLERANCE 10%
J 0
(-1425 2475);
DISPLAY 0.638298 (-1425 2475);
FORCEPROP 1 LAST VALUE 0.1UF
J 0
(-1425 2575);
DISPLAY 0.638298 (-1425 2575);
FORCEPROP 2 LAST CDS_LIB pure_quanta
J 0
(-1475 2525);
DISPLAY INVISIBLE (-1475 2525);
FORCEPROP 1 LAST PATH I68
J 0
(-1425 2675);
DISPLAY 0.978723 (-1425 2675);
PAINT WHITE (-1425 2675);
DISPLAY INVISIBLE (-1425 2675);
FORCEPROP 1 LAST PART_NUMBER CH4102K6E00
J 0
(-1425 2375);
DISPLAY 0.978723 (-1425 2375);
DISPLAY INVISIBLE (-1425 2375);
FORCEADD Q_CAP..1
(-1225 2525);
FORCEPROP 1 LAST LOCATION C968
J 0
(-1175 2625);
DISPLAY 0.978723 (-1175 2625);
PAINT WHITE (-1175 2625);
FORCEPROP 0 LAST $SEC 1
J 0
(-1175 2675);
DISPLAY 0.680851 (-1175 2675);
PAINT MONO (-1175 2675);
DISPLAY INVISIBLE (-1175 2675);
FORCEPROP 0 LAST CDS_SEC 1
J 0
(-1175 2675);
DISPLAY 0.680851 (-1175 2675);
DISPLAY INVISIBLE (-1175 2675);
FORCEPROP 1 LASTPIN (-1225 2625) $PN 1
J 0
(-1215 2605);
DISPLAY 0.787234 (-1215 2605);
PAINT MONO (-1215 2605);
FORCEPROP 1 LASTPIN (-1225 2425) $PN 2
J 0
(-1215 2405);
DISPLAY 0.787234 (-1215 2405);
PAINT MONO (-1215 2405);
FORCEPROP 1 LAST TOLERANCE 10%
J 0
(-1175 2475);
DISPLAY 0.638298 (-1175 2475);
FORCEPROP 1 LAST VOLTAGE 10V
J 0
(-1175 2525);
DISPLAY 0.638298 (-1175 2525);
FORCEPROP 1 LAST MATERIAL X7S
J 0
(-1175 2425);
DISPLAY 0.638298 (-1175 2425);
FORCEPROP 1 LAST PACK_TYPE C0201
J 0
(-1175 2375);
DISPLAY 0.638298 (-1175 2375);
FORCEPROP 1 LAST VALUE 0.1UF
J 0
(-1175 2575);
DISPLAY 0.638298 (-1175 2575);
FORCEPROP 2 LAST CDS_LIB pure_quanta
J 0
(-1225 2525);
DISPLAY INVISIBLE (-1225 2525);
FORCEPROP 1 LAST PATH I69
J 0
(-1175 2675);
DISPLAY 0.978723 (-1175 2675);
PAINT WHITE (-1175 2675);
DISPLAY INVISIBLE (-1175 2675);
FORCEPROP 1 LAST PART_NUMBER CH4102K6E00
J 0
(-1175 2375);
DISPLAY 0.978723 (-1175 2375);
DISPLAY INVISIBLE (-1175 2375);
FORCEADD Q_CAP..1
(-6825 4475);
FORCEPROP 1 LAST LOCATION C668
J 0
(-6775 4575);
DISPLAY 0.638298 (-6775 4575);
PAINT WHITE (-6775 4575);
FORCEPROP 0 LAST $SEC 1
J 0
(-6775 4600);
DISPLAY 0.680851 (-6775 4600);
PAINT MONO (-6775 4600);
DISPLAY INVISIBLE (-6775 4600);
FORCEPROP 0 LAST CDS_SEC 1
J 0
(-6775 4600);
DISPLAY 0.680851 (-6775 4600);
DISPLAY INVISIBLE (-6775 4600);
FORCEPROP 1 LASTPIN (-6825 4575) $PN 1
J 0
(-6815 4555);
DISPLAY 0.787234 (-6815 4555);
PAINT MONO (-6815 4555);
FORCEPROP 1 LASTPIN (-6825 4375) $PN 2
J 0
(-6815 4355);
DISPLAY 0.787234 (-6815 4355);
PAINT MONO (-6815 4355);
FORCEPROP 1 LAST PACK_TYPE C0402
J 0
(-6775 4325);
DISPLAY 0.510638 (-6775 4325);
FORCEPROP 1 LAST MATERIAL X6S
J 0
(-6775 4375);
DISPLAY 0.510638 (-6775 4375);
FORCEPROP 1 LAST TOLERANCE 20%
J 0
(-6775 4425);
DISPLAY 0.510638 (-6775 4425);
FORCEPROP 1 LAST VOLTAGE 4V
J 0
(-6775 4475);
DISPLAY 0.510638 (-6775 4475);
FORCEPROP 1 LAST VALUE 22UF
J 0
(-6775 4525);
DISPLAY 0.510638 (-6775 4525);
FORCEPROP 2 LAST CDS_LIB pure_quanta
J 0
(-6825 4475);
DISPLAY INVISIBLE (-6825 4475);
FORCEPROP 1 LAST PATH I7
J 0
(-6775 4625);
DISPLAY 0.978723 (-6775 4625);
PAINT WHITE (-6775 4625);
DISPLAY INVISIBLE (-6775 4625);
FORCEPROP 1 LAST PART_NUMBER CH622KMEB02
J 0
(-6775 4325);
DISPLAY 0.978723 (-6775 4325);
DISPLAY INVISIBLE (-6775 4325);
FORCEADD UNIVERSAL_GND..1
(-725 2800);
FORCEPROP 3 LASTPIN (-725 2850) SIG_NAME GND\g
J 0
(-715 2860);
DISPLAY 0.659574 (-715 2860);
PAINT MONO (-715 2860);
DISPLAY INVISIBLE (-715 2860);
FORCEPROP 2 LAST CDS_LIB pure_quanta_power
J 0
(-725 2800);
DISPLAY INVISIBLE (-725 2800);
FORCEPROP 1 LAST HDL_POWER GND
J 1
(-700 2725);
DISPLAY 0.872340 (-700 2725);
PAINT GREEN (-700 2725);
DISPLAY INVISIBLE (-700 2725);
FORCEPROP 1 LAST PATH I71
J 0
(-650 2800);
DISPLAY 0.872340 (-650 2800);
PAINT AQUA (-650 2800);
DISPLAY INVISIBLE (-650 2800);
FORCEADD Q_CAP..1
(-1500 3850);
FORCEPROP 1 LAST LOCATION C786
J 0
(-1450 3950);
DISPLAY 0.978723 (-1450 3950);
PAINT WHITE (-1450 3950);
FORCEPROP 0 LAST $SEC 1
J 0
(-1450 4000);
DISPLAY 0.680851 (-1450 4000);
PAINT MONO (-1450 4000);
DISPLAY INVISIBLE (-1450 4000);
FORCEPROP 0 LAST CDS_SEC 1
J 0
(-1450 4000);
DISPLAY 0.680851 (-1450 4000);
DISPLAY INVISIBLE (-1450 4000);
FORCEPROP 1 LASTPIN (-1500 3950) $PN 1
J 0
(-1490 3930);
DISPLAY 0.787234 (-1490 3930);
PAINT MONO (-1490 3930);
FORCEPROP 1 LASTPIN (-1500 3750) $PN 2
J 0
(-1490 3730);
DISPLAY 0.787234 (-1490 3730);
PAINT MONO (-1490 3730);
FORCEPROP 1 LAST PACK_TYPE 0201
J 0
(-1450 3700);
DISPLAY 0.510638 (-1450 3700);
FORCEPROP 1 LAST VOLTAGE 4V
J 0
(-1450 3850);
DISPLAY 0.510638 (-1450 3850);
FORCEPROP 1 LAST VALUE 1UF
J 0
(-1450 3900);
DISPLAY 0.510638 (-1450 3900);
FORCEPROP 1 LAST MATERIAL X6S
J 0
(-1450 3750);
DISPLAY 0.510638 (-1450 3750);
FORCEPROP 1 LAST TOLERANCE 20%
J 0
(-1450 3800);
DISPLAY 0.510638 (-1450 3800);
FORCEPROP 2 LAST CDS_LIB pure_quanta
J 0
(-1500 3850);
DISPLAY INVISIBLE (-1500 3850);
FORCEPROP 1 LAST PATH I72
J 0
(-1450 4000);
DISPLAY 0.978723 (-1450 4000);
PAINT WHITE (-1450 4000);
DISPLAY INVISIBLE (-1450 4000);
FORCEPROP 1 LAST PART_NUMBER CH-10KMEE00
J 0
(-1450 3700);
DISPLAY 0.510638 (-1450 3700);
DISPLAY INVISIBLE (-1450 3700);
FORCEADD Q_CAP..1
(-1250 3850);
FORCEPROP 1 LAST LOCATION C779
J 0
(-1200 3950);
DISPLAY 0.978723 (-1200 3950);
PAINT WHITE (-1200 3950);
FORCEPROP 0 LAST $SEC 1
J 0
(-1200 4000);
DISPLAY 0.680851 (-1200 4000);
PAINT MONO (-1200 4000);
DISPLAY INVISIBLE (-1200 4000);
FORCEPROP 0 LAST CDS_SEC 1
J 0
(-1200 4000);
DISPLAY 0.680851 (-1200 4000);
DISPLAY INVISIBLE (-1200 4000);
FORCEPROP 1 LASTPIN (-1250 3950) $PN 1
J 0
(-1240 3930);
DISPLAY 0.787234 (-1240 3930);
PAINT MONO (-1240 3930);
FORCEPROP 1 LASTPIN (-1250 3750) $PN 2
J 0
(-1240 3730);
DISPLAY 0.787234 (-1240 3730);
PAINT MONO (-1240 3730);
FORCEPROP 1 LAST VOLTAGE 4V
J 0
(-1200 3850);
DISPLAY 0.510638 (-1200 3850);
FORCEPROP 1 LAST PACK_TYPE 0201
J 0
(-1200 3700);
DISPLAY 0.510638 (-1200 3700);
FORCEPROP 1 LAST VALUE 1UF
J 0
(-1200 3900);
DISPLAY 0.510638 (-1200 3900);
FORCEPROP 1 LAST MATERIAL X6S
J 0
(-1200 3750);
DISPLAY 0.510638 (-1200 3750);
FORCEPROP 1 LAST TOLERANCE 20%
J 0
(-1200 3800);
DISPLAY 0.510638 (-1200 3800);
FORCEPROP 2 LAST CDS_LIB pure_quanta
J 0
(-1250 3850);
DISPLAY INVISIBLE (-1250 3850);
FORCEPROP 1 LAST PATH I73
J 0
(-1200 4000);
DISPLAY 0.978723 (-1200 4000);
PAINT WHITE (-1200 4000);
DISPLAY INVISIBLE (-1200 4000);
FORCEPROP 1 LAST PART_NUMBER CH-10KMEE00
J 0
(-1200 3700);
DISPLAY 0.510638 (-1200 3700);
DISPLAY INVISIBLE (-1200 3700);
FORCEADD Q_CAP..1
(-1425 4475);
FORCEPROP 1 LAST LOCATION C986
J 0
(-1375 4575);
DISPLAY 0.978723 (-1375 4575);
PAINT WHITE (-1375 4575);
FORCEPROP 0 LAST $SEC 1
J 0
(-1375 4625);
DISPLAY 0.680851 (-1375 4625);
PAINT MONO (-1375 4625);
DISPLAY INVISIBLE (-1375 4625);
FORCEPROP 0 LAST CDS_SEC 1
J 0
(-1375 4625);
DISPLAY 0.680851 (-1375 4625);
DISPLAY INVISIBLE (-1375 4625);
FORCEPROP 1 LASTPIN (-1425 4575) $PN 1
J 0
(-1415 4555);
DISPLAY 0.787234 (-1415 4555);
PAINT MONO (-1415 4555);
FORCEPROP 1 LASTPIN (-1425 4375) $PN 2
J 0
(-1415 4355);
DISPLAY 0.787234 (-1415 4355);
PAINT MONO (-1415 4355);
FORCEPROP 1 LAST VOLTAGE 6.3V
J 0
(-1375 4475);
DISPLAY 0.510638 (-1375 4475);
FORCEPROP 1 LAST PACK_TYPE C0402
J 0
(-1375 4325);
DISPLAY 0.510638 (-1375 4325);
FORCEPROP 1 LAST MATERIAL X6S
J 0
(-1375 4375);
DISPLAY 0.510638 (-1375 4375);
FORCEPROP 1 LAST VALUE 10UF
J 0
(-1375 4525);
DISPLAY 0.510638 (-1375 4525);
FORCEPROP 1 LAST TOLERANCE 20%
J 0
(-1375 4425);
DISPLAY 0.510638 (-1375 4425);
FORCEPROP 2 LAST CDS_LIB pure_quanta
J 0
(-1425 4475);
DISPLAY INVISIBLE (-1425 4475);
FORCEPROP 1 LAST PATH I74
J 0
(-1375 4625);
DISPLAY 0.978723 (-1375 4625);
PAINT WHITE (-1375 4625);
DISPLAY INVISIBLE (-1375 4625);
FORCEPROP 1 LAST PART_NUMBER CH6101MEB01
J 0
(-1375 4325);
DISPLAY 0.978723 (-1375 4325);
DISPLAY INVISIBLE (-1375 4325);
FORCEADD Q_CAP..1
(-1125 4475);
FORCEPROP 1 LAST LOCATION C973
J 0
(-1075 4575);
DISPLAY 0.978723 (-1075 4575);
PAINT WHITE (-1075 4575);
FORCEPROP 0 LAST $SEC 1
J 0
(-1075 4625);
DISPLAY 0.680851 (-1075 4625);
PAINT MONO (-1075 4625);
DISPLAY INVISIBLE (-1075 4625);
FORCEPROP 0 LAST CDS_SEC 1
J 0
(-1075 4625);
DISPLAY 0.680851 (-1075 4625);
DISPLAY INVISIBLE (-1075 4625);
FORCEPROP 1 LASTPIN (-1125 4575) $PN 1
J 0
(-1115 4555);
DISPLAY 0.787234 (-1115 4555);
PAINT MONO (-1115 4555);
FORCEPROP 1 LASTPIN (-1125 4375) $PN 2
J 0
(-1115 4355);
DISPLAY 0.787234 (-1115 4355);
PAINT MONO (-1115 4355);
FORCEPROP 1 LAST PACK_TYPE C0402
J 0
(-1075 4325);
DISPLAY 0.510638 (-1075 4325);
FORCEPROP 1 LAST TOLERANCE 20%
J 0
(-1075 4425);
DISPLAY 0.510638 (-1075 4425);
FORCEPROP 1 LAST MATERIAL X6S
J 0
(-1075 4375);
DISPLAY 0.510638 (-1075 4375);
FORCEPROP 1 LAST VOLTAGE 6.3V
J 0
(-1075 4475);
DISPLAY 0.510638 (-1075 4475);
FORCEPROP 1 LAST VALUE 10UF
J 0
(-1075 4525);
DISPLAY 0.510638 (-1075 4525);
FORCEPROP 2 LAST CDS_LIB pure_quanta
J 0
(-1125 4475);
DISPLAY INVISIBLE (-1125 4475);
FORCEPROP 1 LAST PATH I75
J 0
(-1075 4625);
DISPLAY 0.978723 (-1075 4625);
PAINT WHITE (-1075 4625);
DISPLAY INVISIBLE (-1075 4625);
FORCEPROP 1 LAST PART_NUMBER CH6101MEB01
J 0
(-1075 4325);
DISPLAY 0.978723 (-1075 4325);
DISPLAY INVISIBLE (-1075 4325);
FORCEADD VCC_CORE..1
(-3325 5125);
FORCEPROP 3 LASTPIN (-3325 5075) SIG_NAME P0V9_CPU0_RT2_2A\g
J 0
(-3315 5085);
DISPLAY 0.659574 (-3315 5085);
PAINT MONO (-3315 5085);
DISPLAY INVISIBLE (-3315 5085);
FORCEPROP 1 LAST HDL_POWER P0V9_CPU0_RT2_2A
J 1
(-3325 5175);
DISPLAY 0.617021 (-3325 5175);
PAINT GREEN (-3325 5175);
FORCEPROP 2 LAST CDS_LIB pure_quanta_power
J 0
(-3325 5125);
DISPLAY INVISIBLE (-3325 5125);
FORCEPROP 1 LAST PATH I76
J 0
(-3275 5150);
DISPLAY 0.872340 (-3275 5150);
PAINT AQUA (-3275 5150);
DISPLAY INVISIBLE (-3275 5150);
FORCEADD Q_CAP..1
(-3275 5750);
FORCEPROP 1 LAST LOCATION C801
J 0
(-3225 5850);
DISPLAY 0.978723 (-3225 5850);
PAINT WHITE (-3225 5850);
FORCEPROP 0 LAST $SEC 1
J 0
(-3225 5900);
DISPLAY 0.680851 (-3225 5900);
PAINT MONO (-3225 5900);
DISPLAY INVISIBLE (-3225 5900);
FORCEPROP 0 LAST CDS_SEC 1
J 0
(-3225 5900);
DISPLAY 0.680851 (-3225 5900);
DISPLAY INVISIBLE (-3225 5900);
FORCEPROP 1 LASTPIN (-3275 5850) $PN 1
J 0
(-3265 5830);
DISPLAY 0.787234 (-3265 5830);
PAINT MONO (-3265 5830);
FORCEPROP 1 LASTPIN (-3275 5650) $PN 2
J 0
(-3265 5630);
DISPLAY 0.787234 (-3265 5630);
PAINT MONO (-3265 5630);
FORCEPROP 1 LAST MATERIAL X6S
J 0
(-3225 5650);
DISPLAY 0.510638 (-3225 5650);
FORCEPROP 1 LAST PACK_TYPE C0805
J 0
(-3225 5600);
DISPLAY 0.510638 (-3225 5600);
FORCEPROP 1 LAST TOLERANCE 20%
J 0
(-3225 5700);
DISPLAY 0.510638 (-3225 5700);
FORCEPROP 1 LAST VOLTAGE 4V
J 0
(-3225 5750);
DISPLAY 0.510638 (-3225 5750);
FORCEPROP 1 LAST VALUE 100UF
J 0
(-3225 5800);
DISPLAY 0.510638 (-3225 5800);
FORCEPROP 2 LAST CDS_LIB pure_quanta
J 0
(-3275 5750);
DISPLAY INVISIBLE (-3275 5750);
FORCEPROP 1 LAST PATH I77
J 0
(-3225 5900);
DISPLAY 0.978723 (-3225 5900);
PAINT WHITE (-3225 5900);
DISPLAY INVISIBLE (-3225 5900);
FORCEPROP 1 LAST PART_NUMBER CH710KMEA01
J 0
(-3225 5600);
DISPLAY 0.404255 (-3225 5600);
DISPLAY INVISIBLE (-3225 5600);
FORCEADD Q_CAP..1
(-3000 5750);
FORCEPROP 1 LAST LOCATION C805
J 0
(-2950 5850);
DISPLAY 0.978723 (-2950 5850);
PAINT WHITE (-2950 5850);
FORCEPROP 0 LAST $SEC 1
J 0
(-2950 5900);
DISPLAY 0.680851 (-2950 5900);
PAINT MONO (-2950 5900);
DISPLAY INVISIBLE (-2950 5900);
FORCEPROP 0 LAST CDS_SEC 1
J 0
(-2950 5900);
DISPLAY 0.680851 (-2950 5900);
DISPLAY INVISIBLE (-2950 5900);
FORCEPROP 1 LASTPIN (-3000 5850) $PN 1
J 0
(-2990 5830);
DISPLAY 0.787234 (-2990 5830);
PAINT MONO (-2990 5830);
FORCEPROP 1 LASTPIN (-3000 5650) $PN 2
J 0
(-2990 5630);
DISPLAY 0.787234 (-2990 5630);
PAINT MONO (-2990 5630);
FORCEPROP 1 LAST VOLTAGE 4V
J 0
(-2950 5750);
DISPLAY 0.510638 (-2950 5750);
FORCEPROP 1 LAST PACK_TYPE C0402
J 0
(-2950 5600);
DISPLAY 0.510638 (-2950 5600);
FORCEPROP 1 LAST MATERIAL X6S
J 0
(-2950 5650);
DISPLAY 0.510638 (-2950 5650);
FORCEPROP 1 LAST TOLERANCE 20%
J 0
(-2950 5700);
DISPLAY 0.510638 (-2950 5700);
FORCEPROP 1 LAST VALUE 22UF
J 0
(-2950 5800);
DISPLAY 0.510638 (-2950 5800);
FORCEPROP 2 LAST CDS_LIB pure_quanta
J 0
(-3000 5750);
DISPLAY INVISIBLE (-3000 5750);
FORCEPROP 1 LAST PATH I78
J 0
(-2950 5900);
DISPLAY 0.978723 (-2950 5900);
PAINT WHITE (-2950 5900);
DISPLAY INVISIBLE (-2950 5900);
FORCEPROP 1 LAST PART_NUMBER CH622KMEB02
J 0
(-2950 5600);
DISPLAY 0.978723 (-2950 5600);
DISPLAY INVISIBLE (-2950 5600);
FORCEADD Q_CAP..1
(-2675 5725);
FORCEPROP 1 LAST LOCATION C971
J 0
(-2625 5825);
DISPLAY 0.978723 (-2625 5825);
PAINT WHITE (-2625 5825);
FORCEPROP 0 LAST $SEC 1
J 0
(-2625 5875);
DISPLAY 0.680851 (-2625 5875);
PAINT MONO (-2625 5875);
DISPLAY INVISIBLE (-2625 5875);
FORCEPROP 0 LAST CDS_SEC 1
J 0
(-2625 5875);
DISPLAY 0.680851 (-2625 5875);
DISPLAY INVISIBLE (-2625 5875);
FORCEPROP 1 LASTPIN (-2675 5825) $PN 1
J 0
(-2665 5805);
DISPLAY 0.787234 (-2665 5805);
PAINT MONO (-2665 5805);
FORCEPROP 1 LASTPIN (-2675 5625) $PN 2
J 0
(-2665 5605);
DISPLAY 0.787234 (-2665 5605);
PAINT MONO (-2665 5605);
FORCEPROP 1 LAST VALUE 10UF
J 0
(-2625 5775);
DISPLAY 0.510638 (-2625 5775);
FORCEPROP 1 LAST VOLTAGE 6.3V
J 0
(-2625 5725);
DISPLAY 0.510638 (-2625 5725);
FORCEPROP 1 LAST TOLERANCE 20%
J 0
(-2625 5675);
DISPLAY 0.510638 (-2625 5675);
FORCEPROP 1 LAST MATERIAL X6S
J 0
(-2625 5625);
DISPLAY 0.510638 (-2625 5625);
FORCEPROP 1 LAST PACK_TYPE C0402
J 0
(-2625 5575);
DISPLAY 0.510638 (-2625 5575);
FORCEPROP 2 LAST CDS_LIB pure_quanta
J 0
(-2675 5725);
DISPLAY INVISIBLE (-2675 5725);
FORCEPROP 1 LAST PATH I79
J 0
(-2625 5875);
DISPLAY 0.978723 (-2625 5875);
PAINT WHITE (-2625 5875);
DISPLAY INVISIBLE (-2625 5875);
FORCEPROP 1 LAST PART_NUMBER CH6101MEB01
J 0
(-2625 5575);
DISPLAY 0.978723 (-2625 5575);
DISPLAY INVISIBLE (-2625 5575);
FORCEADD UNIVERSAL_GND..1
(-6350 2975);
FORCEPROP 3 LASTPIN (-6350 3025) SIG_NAME GND\g
J 0
(-6340 3035);
DISPLAY 0.659574 (-6340 3035);
PAINT MONO (-6340 3035);
DISPLAY INVISIBLE (-6340 3035);
FORCEPROP 2 LAST CDS_LIB pure_quanta_power
J 0
(-6350 2975);
DISPLAY INVISIBLE (-6350 2975);
FORCEPROP 1 LAST HDL_POWER GND
J 1
(-6325 2900);
DISPLAY 0.872340 (-6325 2900);
PAINT GREEN (-6325 2900);
DISPLAY INVISIBLE (-6325 2900);
FORCEPROP 1 LAST PATH I8
J 0
(-6275 2975);
DISPLAY 0.872340 (-6275 2975);
PAINT AQUA (-6275 2975);
DISPLAY INVISIBLE (-6275 2975);
FORCEADD Q_CAP..1
(-2375 5725);
FORCEPROP 1 LAST LOCATION C976
J 0
(-2325 5825);
DISPLAY 0.978723 (-2325 5825);
PAINT WHITE (-2325 5825);
FORCEPROP 0 LAST $SEC 1
J 0
(-2325 5875);
DISPLAY 0.680851 (-2325 5875);
PAINT MONO (-2325 5875);
DISPLAY INVISIBLE (-2325 5875);
FORCEPROP 0 LAST CDS_SEC 1
J 0
(-2325 5875);
DISPLAY 0.680851 (-2325 5875);
DISPLAY INVISIBLE (-2325 5875);
FORCEPROP 1 LASTPIN (-2375 5825) $PN 1
J 0
(-2365 5805);
DISPLAY 0.787234 (-2365 5805);
PAINT MONO (-2365 5805);
FORCEPROP 1 LASTPIN (-2375 5625) $PN 2
J 0
(-2365 5605);
DISPLAY 0.787234 (-2365 5605);
PAINT MONO (-2365 5605);
FORCEPROP 1 LAST VOLTAGE 6.3V
J 0
(-2325 5725);
DISPLAY 0.510638 (-2325 5725);
FORCEPROP 1 LAST VALUE 4.7UF
J 0
(-2325 5775);
DISPLAY 0.510638 (-2325 5775);
FORCEPROP 1 LAST MATERIAL X6S
J 0
(-2325 5625);
DISPLAY 0.510638 (-2325 5625);
FORCEPROP 1 LAST TOLERANCE 20%
J 0
(-2325 5675);
DISPLAY 0.510638 (-2325 5675);
FORCEPROP 1 LAST PACK_TYPE 0402
J 0
(-2325 5575);
DISPLAY 0.510638 (-2325 5575);
FORCEPROP 2 LAST CDS_LIB pure_quanta
J 0
(-2375 5725);
DISPLAY INVISIBLE (-2375 5725);
FORCEPROP 1 LAST PATH I80
J 0
(-2325 5875);
DISPLAY 0.978723 (-2325 5875);
PAINT WHITE (-2325 5875);
DISPLAY INVISIBLE (-2325 5875);
FORCEPROP 1 LAST PART_NUMBER CH5471MEB01
J 0
(-2325 5575);
DISPLAY 0.978723 (-2325 5575);
DISPLAY INVISIBLE (-2325 5575);
FORCEADD Q_CAP..1
(-2075 5725);
FORCEPROP 1 LAST LOCATION C980
J 0
(-2025 5825);
DISPLAY 0.978723 (-2025 5825);
PAINT WHITE (-2025 5825);
FORCEPROP 0 LAST $SEC 1
J 0
(-2025 5875);
DISPLAY 0.680851 (-2025 5875);
PAINT MONO (-2025 5875);
DISPLAY INVISIBLE (-2025 5875);
FORCEPROP 0 LAST CDS_SEC 1
J 0
(-2025 5875);
DISPLAY 0.680851 (-2025 5875);
DISPLAY INVISIBLE (-2025 5875);
FORCEPROP 1 LASTPIN (-2075 5825) $PN 1
J 0
(-2065 5805);
DISPLAY 0.787234 (-2065 5805);
PAINT MONO (-2065 5805);
FORCEPROP 1 LASTPIN (-2075 5625) $PN 2
J 0
(-2065 5605);
DISPLAY 0.787234 (-2065 5605);
PAINT MONO (-2065 5605);
FORCEPROP 1 LAST TOLERANCE 20%
J 0
(-2025 5675);
DISPLAY 0.510638 (-2025 5675);
FORCEPROP 1 LAST VALUE 1UF
J 0
(-2025 5775);
DISPLAY 0.510638 (-2025 5775);
FORCEPROP 1 LAST MATERIAL X6S
J 0
(-2025 5625);
DISPLAY 0.510638 (-2025 5625);
FORCEPROP 1 LAST VOLTAGE 4V
J 0
(-2025 5725);
DISPLAY 0.510638 (-2025 5725);
FORCEPROP 1 LAST PACK_TYPE 0201
J 0
(-2025 5575);
DISPLAY 0.510638 (-2025 5575);
FORCEPROP 2 LAST CDS_LIB pure_quanta
J 0
(-2075 5725);
DISPLAY INVISIBLE (-2075 5725);
FORCEPROP 1 LAST PATH I81
J 0
(-2025 5875);
DISPLAY 0.978723 (-2025 5875);
PAINT WHITE (-2025 5875);
DISPLAY INVISIBLE (-2025 5875);
FORCEPROP 1 LAST PART_NUMBER CH-10KMEE00
J 0
(-2025 5575);
DISPLAY 0.510638 (-2025 5575);
DISPLAY INVISIBLE (-2025 5575);
FORCEADD Q_CAP..1
(-1775 5700);
FORCEPROP 1 LAST LOCATION C780
J 0
(-1725 5800);
DISPLAY 0.978723 (-1725 5800);
PAINT WHITE (-1725 5800);
FORCEPROP 0 LAST $SEC 1
J 0
(-1725 5850);
DISPLAY 0.680851 (-1725 5850);
PAINT MONO (-1725 5850);
DISPLAY INVISIBLE (-1725 5850);
FORCEPROP 0 LAST CDS_SEC 1
J 0
(-1725 5850);
DISPLAY 0.680851 (-1725 5850);
DISPLAY INVISIBLE (-1725 5850);
FORCEPROP 1 LASTPIN (-1775 5800) $PN 1
J 0
(-1765 5780);
DISPLAY 0.787234 (-1765 5780);
PAINT MONO (-1765 5780);
FORCEPROP 1 LASTPIN (-1775 5600) $PN 2
J 0
(-1765 5580);
DISPLAY 0.787234 (-1765 5580);
PAINT MONO (-1765 5580);
FORCEPROP 1 LAST VOLTAGE 10V
J 0
(-1725 5700);
DISPLAY 0.638298 (-1725 5700);
FORCEPROP 1 LAST MATERIAL X7S
J 0
(-1725 5600);
DISPLAY 0.638298 (-1725 5600);
FORCEPROP 1 LAST TOLERANCE 10%
J 0
(-1725 5650);
DISPLAY 0.638298 (-1725 5650);
FORCEPROP 1 LAST VALUE 0.1UF
J 0
(-1725 5750);
DISPLAY 0.638298 (-1725 5750);
FORCEPROP 1 LAST PACK_TYPE C0201
J 0
(-1725 5550);
DISPLAY 0.638298 (-1725 5550);
FORCEPROP 2 LAST CDS_LIB pure_quanta
J 0
(-1775 5700);
DISPLAY INVISIBLE (-1775 5700);
FORCEPROP 1 LAST PATH I82
J 0
(-1725 5850);
DISPLAY 0.978723 (-1725 5850);
PAINT WHITE (-1725 5850);
DISPLAY INVISIBLE (-1725 5850);
FORCEPROP 1 LAST PART_NUMBER CH4102K6E00
J 0
(-1725 5550);
DISPLAY 0.978723 (-1725 5550);
DISPLAY INVISIBLE (-1725 5550);
FORCEADD Q_CAP..1
(-1500 5700);
FORCEPROP 1 LAST LOCATION C782
J 0
(-1450 5800);
DISPLAY 0.978723 (-1450 5800);
PAINT WHITE (-1450 5800);
FORCEPROP 0 LAST $SEC 1
J 0
(-1450 5850);
DISPLAY 0.680851 (-1450 5850);
PAINT MONO (-1450 5850);
DISPLAY INVISIBLE (-1450 5850);
FORCEPROP 0 LAST CDS_SEC 1
J 0
(-1450 5850);
DISPLAY 0.680851 (-1450 5850);
DISPLAY INVISIBLE (-1450 5850);
FORCEPROP 1 LASTPIN (-1500 5800) $PN 1
J 0
(-1490 5780);
DISPLAY 0.787234 (-1490 5780);
PAINT MONO (-1490 5780);
FORCEPROP 1 LASTPIN (-1500 5600) $PN 2
J 0
(-1490 5580);
DISPLAY 0.787234 (-1490 5580);
PAINT MONO (-1490 5580);
FORCEPROP 1 LAST TOLERANCE 10%
J 0
(-1450 5650);
DISPLAY 0.638298 (-1450 5650);
FORCEPROP 1 LAST PACK_TYPE C0201
J 0
(-1450 5550);
DISPLAY 0.638298 (-1450 5550);
FORCEPROP 1 LAST VALUE 0.1UF
J 0
(-1450 5750);
DISPLAY 0.638298 (-1450 5750);
FORCEPROP 1 LAST VOLTAGE 10V
J 0
(-1450 5700);
DISPLAY 0.638298 (-1450 5700);
FORCEPROP 1 LAST MATERIAL X7S
J 0
(-1450 5600);
DISPLAY 0.638298 (-1450 5600);
FORCEPROP 2 LAST CDS_LIB pure_quanta
J 0
(-1500 5700);
DISPLAY INVISIBLE (-1500 5700);
FORCEPROP 1 LAST PATH I83
J 0
(-1450 5850);
DISPLAY 0.978723 (-1450 5850);
PAINT WHITE (-1450 5850);
DISPLAY INVISIBLE (-1450 5850);
FORCEPROP 1 LAST PART_NUMBER CH4102K6E00
J 0
(-1450 5550);
DISPLAY 0.978723 (-1450 5550);
DISPLAY INVISIBLE (-1450 5550);
FORCEADD Q_CAP..1
(-1250 5700);
FORCEPROP 1 LAST LOCATION C785
J 0
(-1200 5800);
DISPLAY 0.978723 (-1200 5800);
PAINT WHITE (-1200 5800);
FORCEPROP 0 LAST $SEC 1
J 0
(-1200 5850);
DISPLAY 0.680851 (-1200 5850);
PAINT MONO (-1200 5850);
DISPLAY INVISIBLE (-1200 5850);
FORCEPROP 0 LAST CDS_SEC 1
J 0
(-1200 5850);
DISPLAY 0.680851 (-1200 5850);
DISPLAY INVISIBLE (-1200 5850);
FORCEPROP 1 LASTPIN (-1250 5800) $PN 1
J 0
(-1240 5780);
DISPLAY 0.787234 (-1240 5780);
PAINT MONO (-1240 5780);
FORCEPROP 1 LASTPIN (-1250 5600) $PN 2
J 0
(-1240 5580);
DISPLAY 0.787234 (-1240 5580);
PAINT MONO (-1240 5580);
FORCEPROP 1 LAST TOLERANCE 10%
J 0
(-1200 5650);
DISPLAY 0.638298 (-1200 5650);
FORCEPROP 1 LAST VALUE 0.1UF
J 0
(-1200 5750);
DISPLAY 0.638298 (-1200 5750);
FORCEPROP 1 LAST VOLTAGE 10V
J 0
(-1200 5700);
DISPLAY 0.638298 (-1200 5700);
FORCEPROP 1 LAST MATERIAL X7S
J 0
(-1200 5600);
DISPLAY 0.638298 (-1200 5600);
FORCEPROP 1 LAST PACK_TYPE C0201
J 0
(-1200 5550);
DISPLAY 0.638298 (-1200 5550);
FORCEPROP 2 LAST CDS_LIB pure_quanta
J 0
(-1250 5700);
DISPLAY INVISIBLE (-1250 5700);
FORCEPROP 1 LAST PATH I84
J 0
(-1200 5850);
DISPLAY 0.978723 (-1200 5850);
PAINT WHITE (-1200 5850);
DISPLAY INVISIBLE (-1200 5850);
FORCEPROP 1 LAST PART_NUMBER CH4102K6E00
J 0
(-1200 5550);
DISPLAY 0.978723 (-1200 5550);
DISPLAY INVISIBLE (-1200 5550);
FORCEADD UNIVERSAL_GND..1
(-1050 5300);
FORCEPROP 3 LASTPIN (-1050 5350) SIG_NAME GND\g
J 0
(-1040 5360);
DISPLAY 0.659574 (-1040 5360);
PAINT MONO (-1040 5360);
DISPLAY INVISIBLE (-1040 5360);
FORCEPROP 2 LAST CDS_LIB pure_quanta_power
J 0
(-1050 5300);
DISPLAY INVISIBLE (-1050 5300);
FORCEPROP 1 LAST HDL_POWER GND
J 1
(-1025 5225);
DISPLAY 0.872340 (-1025 5225);
PAINT GREEN (-1025 5225);
DISPLAY INVISIBLE (-1025 5225);
FORCEPROP 1 LAST PATH I85
J 0
(-975 5300);
DISPLAY 0.872340 (-975 5300);
PAINT AQUA (-975 5300);
DISPLAY INVISIBLE (-975 5300);
FORCEADD Q_CAP..1
(-975 5700);
FORCEPROP 1 LAST LOCATION C789
J 0
(-925 5800);
DISPLAY 0.978723 (-925 5800);
PAINT WHITE (-925 5800);
FORCEPROP 0 LAST $SEC 1
J 0
(-925 5850);
DISPLAY 0.680851 (-925 5850);
PAINT MONO (-925 5850);
DISPLAY INVISIBLE (-925 5850);
FORCEPROP 0 LAST CDS_SEC 1
J 0
(-925 5850);
DISPLAY 0.680851 (-925 5850);
DISPLAY INVISIBLE (-925 5850);
FORCEPROP 1 LASTPIN (-975 5800) $PN 1
J 0
(-965 5780);
DISPLAY 0.787234 (-965 5780);
PAINT MONO (-965 5780);
FORCEPROP 1 LASTPIN (-975 5600) $PN 2
J 0
(-965 5580);
DISPLAY 0.787234 (-965 5580);
PAINT MONO (-965 5580);
FORCEPROP 1 LAST PACK_TYPE C0201
J 0
(-925 5550);
DISPLAY 0.638298 (-925 5550);
FORCEPROP 1 LAST MATERIAL X7S
J 0
(-925 5600);
DISPLAY 0.638298 (-925 5600);
FORCEPROP 1 LAST VALUE 0.1UF
J 0
(-925 5750);
DISPLAY 0.638298 (-925 5750);
FORCEPROP 1 LAST VOLTAGE 10V
J 0
(-925 5700);
DISPLAY 0.638298 (-925 5700);
FORCEPROP 1 LAST TOLERANCE 10%
J 0
(-925 5650);
DISPLAY 0.638298 (-925 5650);
FORCEPROP 2 LAST CDS_LIB pure_quanta
J 0
(-975 5700);
DISPLAY INVISIBLE (-975 5700);
FORCEPROP 1 LAST PATH I86
J 0
(-925 5850);
DISPLAY 0.978723 (-925 5850);
PAINT WHITE (-925 5850);
DISPLAY INVISIBLE (-925 5850);
FORCEPROP 1 LAST PART_NUMBER CH4102K6E00
J 0
(-925 5550);
DISPLAY 0.978723 (-925 5550);
DISPLAY INVISIBLE (-925 5550);
FORCEADD Q_CAP..1
(-3100 3850);
FORCEPROP 1 LAST LOCATION C803
J 0
(-3050 3950);
DISPLAY 0.978723 (-3050 3950);
PAINT WHITE (-3050 3950);
FORCEPROP 0 LAST $SEC 1
J 0
(-3050 4000);
DISPLAY 0.680851 (-3050 4000);
PAINT MONO (-3050 4000);
DISPLAY INVISIBLE (-3050 4000);
FORCEPROP 0 LAST CDS_SEC 1
J 0
(-3050 4000);
DISPLAY 0.680851 (-3050 4000);
DISPLAY INVISIBLE (-3050 4000);
FORCEPROP 1 LASTPIN (-3100 3950) $PN 1
J 0
(-3090 3930);
DISPLAY 0.787234 (-3090 3930);
PAINT MONO (-3090 3930);
FORCEPROP 1 LASTPIN (-3100 3750) $PN 2
J 0
(-3090 3730);
DISPLAY 0.787234 (-3090 3730);
PAINT MONO (-3090 3730);
FORCEPROP 1 LAST VALUE 10UF
J 0
(-3050 3900);
DISPLAY 0.510638 (-3050 3900);
FORCEPROP 1 LAST MATERIAL X6S
J 0
(-3050 3750);
DISPLAY 0.510638 (-3050 3750);
FORCEPROP 1 LAST VOLTAGE 6.3V
J 0
(-3050 3850);
DISPLAY 0.510638 (-3050 3850);
FORCEPROP 1 LAST TOLERANCE 20%
J 0
(-3050 3800);
DISPLAY 0.510638 (-3050 3800);
FORCEPROP 1 LAST PACK_TYPE C0402
J 0
(-3050 3700);
DISPLAY 0.510638 (-3050 3700);
FORCEPROP 2 LAST CDS_LIB pure_quanta
J 0
(-3100 3850);
DISPLAY INVISIBLE (-3100 3850);
FORCEPROP 1 LAST PATH I87
J 0
(-3050 4000);
DISPLAY 0.978723 (-3050 4000);
PAINT WHITE (-3050 4000);
DISPLAY INVISIBLE (-3050 4000);
FORCEPROP 1 LAST PART_NUMBER CH6101MEB01
J 0
(-3050 3700);
DISPLAY 0.978723 (-3050 3700);
DISPLAY INVISIBLE (-3050 3700);
FORCEADD Q_INDUCTOR..1
R 3
(-8075 4400);
FORCEPROP 1 LAST LOCATION L29
R 1
J 2
(-8225 4525);
DISPLAY 0.574468 (-8225 4525);
PAINT GREEN (-8225 4525);
FORCEPROP 0 LAST $SEC 1
R 1
J 0
(-8050 4525);
DISPLAY 0.680851 (-8050 4525);
PAINT MONO (-8050 4525);
DISPLAY INVISIBLE (-8050 4525);
FORCEPROP 0 LAST CDS_SEC 1
R 1
J 0
(-8050 4525);
DISPLAY 0.680851 (-8050 4525);
DISPLAY INVISIBLE (-8050 4525);
FORCEPROP 0 LASTPIN (-8050 4500) $PN 1
R 1
J 0
(-8060 4510);
DISPLAY 0.680851 (-8060 4510);
PAINT MONO (-8060 4510);
FORCEPROP 0 LASTPIN (-8050 4300) $PN 2
R 1
J 2
(-8060 4290);
DISPLAY 0.680851 (-8060 4290);
PAINT MONO (-8060 4290);
FORCEPROP 2 LAST PACK_TYPE SMLF
R 1
J 2
(-8275 4525);
DISPLAY 0.553191 (-8275 4525);
FORCEPROP 1 LAST MATERIAL IND
R 1
J 2
(-8130 4525);
DISPLAY 0.574468 (-8130 4525);
PAINT GREEN (-8130 4525);
FORCEPROP 2 LAST VALUE BLM15PD121SN1D/1300MA
R 1
J 2
(-8325 4525);
DISPLAY 0.553191 (-8325 4525);
FORCEPROP 2 LAST CDS_LIB pure_quanta
R 1
J 2
(-8075 4400);
DISPLAY INVISIBLE (-8075 4400);
FORCEPROP 1 LAST NEEDS_NO_SIZE TRUE
R 1
J 2
(-8075 4400);
DISPLAY 0.468085 (-8075 4400);
PAINT GREEN (-8075 4400);
DISPLAY INVISIBLE (-8075 4400);
FORCEPROP 1 LAST PATH I88
R 1
J 2
(-8130 4325);
DISPLAY 0.723404 (-8130 4325);
PAINT GREEN (-8130 4325);
DISPLAY INVISIBLE (-8130 4325);
FORCEPROP 1 LAST PART_NUMBER CX5PD121000
R 1
J 2
(-8175 4525);
DISPLAY 0.574468 (-8175 4525);
PAINT GREEN (-8175 4525);
DISPLAY INVISIBLE (-8175 4525);
FORCEADD Q_RES..2
(-7950 4375);
FORCEPROP 1 LAST LOCATION R1050
J 0
(-7905 4500);
DISPLAY 0.808511 (-7905 4500);
FORCEPROP 0 LAST $SEC 1
J 0
(-7900 4550);
DISPLAY 0.680851 (-7900 4550);
PAINT MONO (-7900 4550);
DISPLAY INVISIBLE (-7900 4550);
FORCEPROP 0 LAST CDS_SEC 1
J 0
(-7900 4550);
DISPLAY 0.680851 (-7900 4550);
DISPLAY INVISIBLE (-7900 4550);
FORCEPROP 1 LASTPIN (-7950 4475) $PN 1
J 0
(-7945 4437);
DISPLAY 0.787234 (-7945 4437);
PAINT MONO (-7945 4437);
FORCEPROP 1 LASTPIN (-7950 4275) $PN 2
J 0
(-7945 4285);
DISPLAY 0.787234 (-7945 4285);
PAINT MONO (-7945 4285);
FORCEPROP 1 LAST PACK_TYPE 0402LF
J 0
(-7910 4200);
DISPLAY 0.638298 (-7910 4200);
FORCEPROP 1 LAST MATERIAL EMPTY
J 0
(-7910 4300);
DISPLAY 0.638298 (-7910 4300);
PAINT RED (-7910 4300);
FORCEPROP 1 LAST TOLERANCE 5%
J 0
(-7905 4400);
DISPLAY 0.638298 (-7905 4400);
FORCEPROP 1 LAST VALUE 0
J 0
(-7905 4450);
DISPLAY 0.638298 (-7905 4450);
FORCEPROP 1 LAST WATTAGE 1/16W
J 0
(-7910 4350);
DISPLAY 0.638298 (-7910 4350);
FORCEPROP 2 LAST CDS_LIB pure_quanta
J 0
(-7950 4375);
DISPLAY INVISIBLE (-7950 4375);
FORCEPROP 1 LAST PATH I89
J 0
(-7900 4550);
DISPLAY 0.978723 (-7900 4550);
PAINT WHITE (-7900 4550);
DISPLAY INVISIBLE (-7900 4550);
FORCEPROP 1 LAST PART_NUMBER CS00002JB13
J 0
(-7910 4250);
DISPLAY 0.638298 (-7910 4250);
DISPLAY INVISIBLE (-7910 4250);
FORCEADD Q_CAP..1
(-6625 3400);
FORCEPROP 1 LAST LOCATION C676
J 0
(-6575 3500);
DISPLAY 0.638298 (-6575 3500);
PAINT WHITE (-6575 3500);
FORCEPROP 0 LAST $SEC 1
J 0
(-6575 3550);
DISPLAY 0.680851 (-6575 3550);
PAINT MONO (-6575 3550);
DISPLAY INVISIBLE (-6575 3550);
FORCEPROP 0 LAST CDS_SEC 1
J 0
(-6575 3550);
DISPLAY 0.680851 (-6575 3550);
DISPLAY INVISIBLE (-6575 3550);
FORCEPROP 1 LASTPIN (-6625 3500) $PN 1
J 0
(-6615 3480);
DISPLAY 0.787234 (-6615 3480);
PAINT MONO (-6615 3480);
FORCEPROP 1 LASTPIN (-6625 3300) $PN 2
J 0
(-6615 3280);
DISPLAY 0.787234 (-6615 3280);
PAINT MONO (-6615 3280);
FORCEPROP 1 LAST VALUE 1UF
J 0
(-6575 3450);
DISPLAY 0.510638 (-6575 3450);
FORCEPROP 1 LAST PACK_TYPE 0201
J 0
(-6575 3250);
DISPLAY 0.510638 (-6575 3250);
FORCEPROP 1 LAST MATERIAL X6S
J 0
(-6575 3300);
DISPLAY 0.510638 (-6575 3300);
FORCEPROP 1 LAST TOLERANCE 20%
J 0
(-6575 3350);
DISPLAY 0.510638 (-6575 3350);
FORCEPROP 1 LAST VOLTAGE 4V
J 0
(-6575 3400);
DISPLAY 0.510638 (-6575 3400);
FORCEPROP 2 LAST CDS_LIB pure_quanta
J 0
(-6625 3400);
DISPLAY INVISIBLE (-6625 3400);
FORCEPROP 1 LAST PATH I9
J 0
(-6575 3550);
DISPLAY 0.978723 (-6575 3550);
PAINT WHITE (-6575 3550);
DISPLAY INVISIBLE (-6575 3550);
FORCEPROP 1 LAST PART_NUMBER CH-10KMEE00
J 0
(-6575 3250);
DISPLAY 0.510638 (-6575 3250);
DISPLAY INVISIBLE (-6575 3250);
FORCEADD Q_CAP..1
(-2875 1425);
FORCEPROP 1 LAST LOCATION C787
J 0
(-2825 1525);
DISPLAY 0.978723 (-2825 1525);
PAINT WHITE (-2825 1525);
FORCEPROP 0 LAST $SEC 1
J 0
(-2825 1575);
DISPLAY 0.680851 (-2825 1575);
PAINT MONO (-2825 1575);
DISPLAY INVISIBLE (-2825 1575);
FORCEPROP 0 LAST CDS_SEC 1
J 0
(-2825 1575);
DISPLAY 0.680851 (-2825 1575);
DISPLAY INVISIBLE (-2825 1575);
FORCEPROP 1 LASTPIN (-2875 1525) $PN 1
J 0
(-2865 1505);
DISPLAY 0.787234 (-2865 1505);
PAINT MONO (-2865 1505);
FORCEPROP 1 LASTPIN (-2875 1325) $PN 2
J 0
(-2865 1305);
DISPLAY 0.787234 (-2865 1305);
PAINT MONO (-2865 1305);
FORCEPROP 1 LAST VALUE 1UF
J 0
(-2825 1475);
DISPLAY 0.510638 (-2825 1475);
FORCEPROP 1 LAST MATERIAL X6S
J 0
(-2825 1325);
DISPLAY 0.510638 (-2825 1325);
FORCEPROP 1 LAST VOLTAGE 4V
J 0
(-2825 1425);
DISPLAY 0.510638 (-2825 1425);
FORCEPROP 1 LAST PACK_TYPE 0201
J 0
(-2825 1275);
DISPLAY 0.510638 (-2825 1275);
FORCEPROP 1 LAST TOLERANCE 20%
J 0
(-2825 1375);
DISPLAY 0.510638 (-2825 1375);
FORCEPROP 2 LAST CDS_LIB pure_quanta
J 0
(-2875 1425);
DISPLAY INVISIBLE (-2875 1425);
FORCEPROP 1 LAST PATH I90
J 0
(-2825 1575);
DISPLAY 0.978723 (-2825 1575);
PAINT WHITE (-2825 1575);
DISPLAY INVISIBLE (-2825 1575);
FORCEPROP 1 LAST PART_NUMBER CH-10KMEE00
J 0
(-2825 1275);
DISPLAY 0.510638 (-2825 1275);
DISPLAY INVISIBLE (-2825 1275);
FORCEADD Q_CAP..1
(-2325 1425);
FORCEPROP 1 LAST LOCATION C793
J 0
(-2275 1525);
DISPLAY 0.978723 (-2275 1525);
PAINT WHITE (-2275 1525);
FORCEPROP 0 LAST $SEC 1
J 0
(-2275 1575);
DISPLAY 0.680851 (-2275 1575);
PAINT MONO (-2275 1575);
DISPLAY INVISIBLE (-2275 1575);
FORCEPROP 0 LAST CDS_SEC 1
J 0
(-2275 1575);
DISPLAY 0.680851 (-2275 1575);
DISPLAY INVISIBLE (-2275 1575);
FORCEPROP 1 LASTPIN (-2325 1525) $PN 1
J 0
(-2315 1505);
DISPLAY 0.787234 (-2315 1505);
PAINT MONO (-2315 1505);
FORCEPROP 1 LASTPIN (-2325 1325) $PN 2
J 0
(-2315 1305);
DISPLAY 0.787234 (-2315 1305);
PAINT MONO (-2315 1305);
FORCEPROP 1 LAST MATERIAL X6S
J 0
(-2275 1325);
DISPLAY 0.510638 (-2275 1325);
FORCEPROP 1 LAST VALUE 1UF
J 0
(-2275 1475);
DISPLAY 0.510638 (-2275 1475);
FORCEPROP 1 LAST PACK_TYPE 0201
J 0
(-2275 1275);
DISPLAY 0.510638 (-2275 1275);
FORCEPROP 1 LAST VOLTAGE 4V
J 0
(-2275 1425);
DISPLAY 0.510638 (-2275 1425);
FORCEPROP 1 LAST TOLERANCE 20%
J 0
(-2275 1375);
DISPLAY 0.510638 (-2275 1375);
FORCEPROP 2 LAST CDS_LIB pure_quanta
J 0
(-2325 1425);
DISPLAY INVISIBLE (-2325 1425);
FORCEPROP 1 LAST PATH I91
J 0
(-2275 1575);
DISPLAY 0.978723 (-2275 1575);
PAINT WHITE (-2275 1575);
DISPLAY INVISIBLE (-2275 1575);
FORCEPROP 1 LAST PART_NUMBER CH-10KMEE00
J 0
(-2275 1275);
DISPLAY 0.510638 (-2275 1275);
DISPLAY INVISIBLE (-2275 1275);
FORCEADD Q_CAP..1
(-1575 3200);
FORCEPROP 1 LAST LOCATION C972
J 0
(-1525 3300);
DISPLAY 0.978723 (-1525 3300);
PAINT WHITE (-1525 3300);
FORCEPROP 0 LAST $SEC 1
J 0
(-1525 3350);
DISPLAY 0.680851 (-1525 3350);
PAINT MONO (-1525 3350);
DISPLAY INVISIBLE (-1525 3350);
FORCEPROP 0 LAST CDS_SEC 1
J 0
(-1525 3350);
DISPLAY 0.680851 (-1525 3350);
DISPLAY INVISIBLE (-1525 3350);
FORCEPROP 1 LASTPIN (-1575 3300) $PN 1
J 0
(-1565 3280);
DISPLAY 0.787234 (-1565 3280);
PAINT MONO (-1565 3280);
FORCEPROP 1 LASTPIN (-1575 3100) $PN 2
J 0
(-1565 3080);
DISPLAY 0.787234 (-1565 3080);
PAINT MONO (-1565 3080);
FORCEPROP 1 LAST MATERIAL X7S
J 0
(-1525 3100);
DISPLAY 0.638298 (-1525 3100);
FORCEPROP 1 LAST TOLERANCE 10%
J 0
(-1525 3150);
DISPLAY 0.638298 (-1525 3150);
FORCEPROP 1 LAST VOLTAGE 10V
J 0
(-1525 3200);
DISPLAY 0.638298 (-1525 3200);
FORCEPROP 1 LAST VALUE 0.1UF
J 0
(-1525 3250);
DISPLAY 0.638298 (-1525 3250);
FORCEPROP 1 LAST PACK_TYPE C0201
J 0
(-1525 3050);
DISPLAY 0.638298 (-1525 3050);
FORCEPROP 2 LAST CDS_LIB pure_quanta
J 0
(-1575 3200);
DISPLAY INVISIBLE (-1575 3200);
FORCEPROP 1 LAST PATH I92
J 0
(-1525 3350);
DISPLAY 0.978723 (-1525 3350);
PAINT WHITE (-1525 3350);
DISPLAY INVISIBLE (-1525 3350);
FORCEPROP 1 LAST PART_NUMBER CH4102K6E00
J 0
(-1525 3050);
DISPLAY 0.978723 (-1525 3050);
DISPLAY INVISIBLE (-1525 3050);
FORCEADD Q_CAP..1
(-1325 3200);
FORCEPROP 1 LAST LOCATION C985
J 0
(-1275 3300);
DISPLAY 0.978723 (-1275 3300);
PAINT WHITE (-1275 3300);
FORCEPROP 0 LAST $SEC 1
J 0
(-1275 3350);
DISPLAY 0.680851 (-1275 3350);
PAINT MONO (-1275 3350);
DISPLAY INVISIBLE (-1275 3350);
FORCEPROP 0 LAST CDS_SEC 1
J 0
(-1275 3350);
DISPLAY 0.680851 (-1275 3350);
DISPLAY INVISIBLE (-1275 3350);
FORCEPROP 1 LASTPIN (-1325 3300) $PN 1
J 0
(-1315 3280);
DISPLAY 0.787234 (-1315 3280);
PAINT MONO (-1315 3280);
FORCEPROP 1 LASTPIN (-1325 3100) $PN 2
J 0
(-1315 3080);
DISPLAY 0.787234 (-1315 3080);
PAINT MONO (-1315 3080);
FORCEPROP 1 LAST PACK_TYPE C0201
J 0
(-1275 3050);
DISPLAY 0.638298 (-1275 3050);
FORCEPROP 1 LAST MATERIAL X7S
J 0
(-1275 3100);
DISPLAY 0.638298 (-1275 3100);
FORCEPROP 1 LAST TOLERANCE 10%
J 0
(-1275 3150);
DISPLAY 0.638298 (-1275 3150);
FORCEPROP 1 LAST VOLTAGE 10V
J 0
(-1275 3200);
DISPLAY 0.638298 (-1275 3200);
FORCEPROP 1 LAST VALUE 0.1UF
J 0
(-1275 3250);
DISPLAY 0.638298 (-1275 3250);
FORCEPROP 2 LAST CDS_LIB pure_quanta
J 0
(-1325 3200);
DISPLAY INVISIBLE (-1325 3200);
FORCEPROP 1 LAST PATH I93
J 0
(-1275 3350);
DISPLAY 0.978723 (-1275 3350);
PAINT WHITE (-1275 3350);
DISPLAY INVISIBLE (-1275 3350);
FORCEPROP 1 LAST PART_NUMBER CH4102K6E00
J 0
(-1275 3050);
DISPLAY 0.978723 (-1275 3050);
DISPLAY INVISIBLE (-1275 3050);
FORCEADD Q_CAPP..1
(-975 2525);
FORCEPROP 1 LAST LOCATION C7014
J 0
(-925 2625);
DISPLAY 0.787234 (-925 2625);
FORCEPROP 0 LAST $SEC 1
J 0
(-925 2675);
DISPLAY 0.680851 (-925 2675);
PAINT MONO (-925 2675);
DISPLAY INVISIBLE (-925 2675);
FORCEPROP 0 LAST CDS_SEC 1
J 0
(-925 2675);
DISPLAY 0.680851 (-925 2675);
DISPLAY INVISIBLE (-925 2675);
FORCEPROP 1 LASTPIN (-975 2625) $PN 1
J 0
(-965 2610);
DISPLAY 0.787234 (-965 2610);
PAINT MONO (-965 2610);
FORCEPROP 1 LASTPIN (-975 2425) $PN 2
J 0
(-965 2410);
DISPLAY 0.787234 (-965 2410);
PAINT MONO (-965 2410);
FORCEPROP 1 LAST MATERIAL SPCAP
J 0
(-925 2425);
DISPLAY 0.510638 (-925 2425);
FORCEPROP 1 LAST VOLTAGE 2.5V
J 0
(-925 2475);
DISPLAY 0.510638 (-925 2475);
FORCEPROP 1 LAST PACK_TYPE SMLF
J 0
(-925 2375);
DISPLAY 0.510638 (-925 2375);
FORCEPROP 1 LAST TOLERANCE 20%
J 0
(-925 2525);
DISPLAY 0.510638 (-925 2525);
FORCEPROP 1 LAST VALUE 470UF
J 0
(-925 2575);
DISPLAY 0.510638 (-925 2575);
FORCEPROP 2 LAST CDS_LIB pure_quanta
J 0
(-975 2525);
DISPLAY INVISIBLE (-975 2525);
FORCEPROP 1 LAST PATH I94
J 0
(-925 2675);
DISPLAY 0.978723 (-925 2675);
DISPLAY INVISIBLE (-925 2675);
FORCEPROP 1 LAST PART_NUMBER CH747LM8818
J 0
(-925 2325);
DISPLAY 0.404255 (-925 2325);
DISPLAY INVISIBLE (-925 2325);
FORCEADD Q_CAPP..1
(-675 2525);
FORCEPROP 1 LAST LOCATION C7015
J 0
(-625 2625);
DISPLAY 0.787234 (-625 2625);
FORCEPROP 0 LAST $SEC 1
J 0
(-625 2675);
DISPLAY 0.680851 (-625 2675);
PAINT MONO (-625 2675);
DISPLAY INVISIBLE (-625 2675);
FORCEPROP 0 LAST CDS_SEC 1
J 0
(-625 2675);
DISPLAY 0.680851 (-625 2675);
DISPLAY INVISIBLE (-625 2675);
FORCEPROP 1 LASTPIN (-675 2625) $PN 1
J 0
(-665 2610);
DISPLAY 0.787234 (-665 2610);
PAINT MONO (-665 2610);
FORCEPROP 1 LASTPIN (-675 2425) $PN 2
J 0
(-665 2410);
DISPLAY 0.787234 (-665 2410);
PAINT MONO (-665 2410);
FORCEPROP 1 LAST VALUE 470UF
J 0
(-625 2575);
DISPLAY 0.510638 (-625 2575);
FORCEPROP 1 LAST TOLERANCE 20%
J 0
(-625 2525);
DISPLAY 0.510638 (-625 2525);
FORCEPROP 1 LAST MATERIAL SPCAP
J 0
(-625 2425);
DISPLAY 0.510638 (-625 2425);
FORCEPROP 1 LAST PACK_TYPE SMLF
J 0
(-625 2375);
DISPLAY 0.510638 (-625 2375);
FORCEPROP 1 LAST VOLTAGE 2.5V
J 0
(-625 2475);
DISPLAY 0.510638 (-625 2475);
FORCEPROP 2 LAST CDS_LIB pure_quanta
J 0
(-675 2525);
DISPLAY INVISIBLE (-675 2525);
FORCEPROP 1 LAST PATH I95
J 0
(-625 2675);
DISPLAY 0.978723 (-625 2675);
DISPLAY INVISIBLE (-625 2675);
FORCEPROP 1 LAST PART_NUMBER CH747LM8818
J 0
(-625 2325);
DISPLAY 0.404255 (-625 2325);
DISPLAY INVISIBLE (-625 2325);
FORCEADD Q_CAP..1
(-375 2525);
FORCEPROP 1 LAST LOCATION C7016
J 0
(-325 2625);
DISPLAY 0.638298 (-325 2625);
FORCEPROP 0 LAST $SEC 1
J 0
(-325 2675);
DISPLAY 0.680851 (-325 2675);
PAINT MONO (-325 2675);
DISPLAY INVISIBLE (-325 2675);
FORCEPROP 0 LAST CDS_SEC 1
J 0
(-325 2675);
DISPLAY 0.680851 (-325 2675);
DISPLAY INVISIBLE (-325 2675);
FORCEPROP 1 LASTPIN (-375 2625) $PN 1
J 0
(-365 2605);
DISPLAY 0.787234 (-365 2605);
PAINT MONO (-365 2605);
FORCEPROP 1 LASTPIN (-375 2425) $PN 2
J 0
(-365 2405);
DISPLAY 0.787234 (-365 2405);
PAINT MONO (-365 2405);
FORCEPROP 1 LAST TOLERANCE 20%
J 0
(-325 2475);
DISPLAY 0.638298 (-325 2475);
FORCEPROP 1 LAST MATERIAL X6S
J 0
(-325 2425);
DISPLAY 0.638298 (-325 2425);
FORCEPROP 1 LAST PACK_TYPE C0805
J 0
(-325 2325);
DISPLAY 0.638298 (-325 2325);
FORCEPROP 1 LAST VALUE 100UF
J 0
(-325 2575);
DISPLAY 0.638298 (-325 2575);
FORCEPROP 1 LAST VOLTAGE 4V
J 0
(-325 2525);
DISPLAY 0.638298 (-325 2525);
FORCEPROP 2 LAST CDS_LIB pure_quanta
J 0
(-375 2525);
DISPLAY INVISIBLE (-375 2525);
FORCEPROP 1 LAST PATH I96
J 0
(-325 2675);
DISPLAY 0.978723 (-325 2675);
PAINT WHITE (-325 2675);
DISPLAY INVISIBLE (-325 2675);
FORCEPROP 1 LAST PART_NUMBER CH710KMEA01
J 0
(-325 2375);
DISPLAY 0.638298 (-325 2375);
DISPLAY INVISIBLE (-325 2375);
FORCEADD DNS..2
(-7825 4375);
PAINT RED (-7825 4375);
FORCEPROP 2 LAST CDS_LIB mstr_misc
J 0
(-7825 4375);
DISPLAY INVISIBLE (-7825 4375);
FORCEPROP 1 LAST COMMENT_BODY TRUE
J 0
(-7825 4375);
DISPLAY INVISIBLE (-7825 4375);
FORCEADD DNS..2
(-7525 4000);
PAINT RED (-7525 4000);
FORCEPROP 2 LAST CDS_LIB mstr_misc
J 0
(-7525 4000);
DISPLAY INVISIBLE (-7525 4000);
FORCEPROP 1 LAST COMMENT_BODY TRUE
J 0
(-7525 4000);
DISPLAY INVISIBLE (-7525 4000);
FORCEADD QUANTA_TITLE_BLOCK_C..1
(0 0);
FORCEPROP 0 LAST CDS_CON_LAST_MODIFIED Thu Sep 14 16:13:09 2023
J 0
(-1885 15);
DISPLAY INVISIBLE (-1885 15);
FORCEPROP 1 LAST CUSTOM_TXT_CDS <CON_LAST_MODIFIED>
J 0
(-1885 15);
DISPLAY 0.978723 (-1885 15);
FORCEPROP 2 LAST CUSTOM_TXT_CDS <XR_PAGE_TITLE>
J 0
(-7890 5250);
DISPLAY 0.638298 (-7890 5250);
PAINT PINK (-7890 5250);
DISPLAY INVISIBLE (-7890 5250);
FORCEPROP 1 LAST CUSTOM_TXT_CDS <NAME_2>
J 0
(-3175 50);
FORCEPROP 1 LAST CUSTOM_TXT_CDS <NAME_1>
J 0
(-3175 175);
FORCEPROP 1 LAST CUSTOM_TXT_CDS <Q_NUMBER>
J 0
(-1403 103);
DISPLAY 1.212766 (-1403 103);
FORCEPROP 1 LAST CUSTOM_TXT_CDS <Q_PROJ>
J 0
(-2382 102);
DISPLAY 1.212766 (-2382 102);
FORCEPROP 1 LAST CUSTOM_TXT_CDS <Q_REV>
J 0
(-184 103);
DISPLAY 1.212766 (-184 103);
FORCEPROP 1 LAST CUSTOM_TXT_CDS <CON_PAGE_NUM> OF <CON_TOTAL_PAGES>
J 0
(-446 18);
DISPLAY 0.978723 (-446 18);
FORCEPROP 1 LAST Q_TITLE RETIMER_CPU0_P2 DECAPS(8)
J 0
(-9366 26);
DISPLAY 2.446809 (-9366 26);
PAINT GREEN (-9366 26);
FORCEPROP 2 LAST PAGE_BORDER TRUE
J 0
(-7890 5250);
DISPLAY 0.638298 (-7890 5250);
PAINT PINK (-7890 5250);
DISPLAY INVISIBLE (-7890 5250);
FORCEPROP 1 LAST CDS_LMAN_SYM_OUTLINE -9475,6775,100,-125
J 0
(0 0);
DISPLAY 0.468085 (0 0);
PAINT GREEN (0 0);
DISPLAY INVISIBLE (0 0);
FORCEPROP 2 LAST CDS_LIB pure_quanta
J 0
(0 0);
DISPLAY INVISIBLE (0 0);
FORCEPROP 2 LAST CDS_XR_PAGE_TITLE CR-302 : @T6G_MB_LIB.T6G(SCH_1):PAGE302
J 0
(-7890 5250);
DISPLAY 0.638298 (-7890 5250);
PAINT PINK (-7890 5250);
DISPLAY INVISIBLE (-7890 5250);
FORCEPROP 1 LAST Q_DEPT BU9
J 1
(-3763 49);
DISPLAY 1.957447 (-3763 49);
PAINT GREEN (-3763 49);
DISPLAY INVISIBLE (-3763 49);
FORCEPROP 1 LAST COMMENT_BODY TRUE
J 0
(12 -13);
DISPLAY 0.978723 (12 -13);
PAINT GREEN (12 -13);
DISPLAY INVISIBLE (12 -13);
FORCEADD DNS..2
(-4200 3025);
PAINT RED (-4200 3025);
FORCEPROP 2 LAST CDS_LIB mstr_misc
J 0
(-4200 3025);
DISPLAY INVISIBLE (-4200 3025);
FORCEPROP 1 LAST COMMENT_BODY TRUE
J 0
(-4200 3025);
DISPLAY INVISIBLE (-4200 3025);
FORCEADD CAD_NOTE..1
(-4950 2725);
FORCEPROP 0 LAST S1 R1051 AND R1053 COLAY
J 0
(-5075 2600);
DISPLAY 0.808511 (-5075 2600);
PAINT WHITE (-5075 2600);
FORCEPROP 2 LAST CDS_LIB pure_quanta_power
J 0
(-4950 2725);
DISPLAY INVISIBLE (-4950 2725);
FORCEPROP 1 LAST COMMENT_BODY TRUE
J 0
(-4925 2825);
DISPLAY 0.978723 (-4925 2825);
DISPLAY INVISIBLE (-4925 2825);
FORCEADD DNS..2
(-7525 3825);
PAINT RED (-7525 3825);
FORCEPROP 2 LAST CDS_LIB mstr_misc
J 0
(-7525 3825);
DISPLAY INVISIBLE (-7525 3825);
FORCEPROP 1 LAST COMMENT_BODY TRUE
J 0
(-7525 3825);
DISPLAY INVISIBLE (-7525 3825);
FORCEADD CAD_NOTE..1
(-8000 3225);
FORCEPROP 0 LAST S1 L29/R1050 COLAY WITH R1045/R1046
J 0
(-8125 3100);
DISPLAY 0.808511 (-8125 3100);
PAINT WHITE (-8125 3100);
FORCEPROP 2 LAST CDS_LIB pure_quanta_power
J 0
(-8000 3225);
DISPLAY INVISIBLE (-8000 3225);
FORCEPROP 1 LAST COMMENT_BODY TRUE
J 0
(-7975 3325);
DISPLAY 0.978723 (-7975 3325);
DISPLAY INVISIBLE (-7975 3325);
WIRE 16 -1 (-375 2775)(-375 2625);
WIRE 16 -1 (-675 2775)(-375 2775);
WIRE 16 -1 (-675 2625)(-675 2775);
WIRE 16 -1 (-975 2775)(-675 2775);
WIRE 16 -1 (-975 2625)(-975 2775);
WIRE 16 -1 (-1225 2775)(-975 2775);
WIRE 16 -1 (-1225 2625)(-1225 2775);
WIRE 16 -1 (-1225 2775)(-1475 2775);
WIRE 16 -1 (-1475 2625)(-1475 2775);
WIRE 16 -1 (-1750 2775)(-1475 2775);
WIRE 16 -1 (-1750 2625)(-1750 2775);
WIRE 16 -1 (-2025 2775)(-1750 2775);
WIRE 16 -1 (-2025 2625)(-2025 2775);
WIRE 16 -1 (-2275 2775)(-2025 2775);
WIRE 16 -1 (-2275 2625)(-2275 2775);
WIRE 16 -1 (-2525 2775)(-2275 2775);
WIRE 16 -1 (-2525 2775)(-2525 2625);
WIRE 16 -1 (-2750 2775)(-2525 2775);
WIRE 16 -1 (-2750 2775)(-2750 2625);
WIRE 16 -1 (-3050 2775)(-2750 2775);
WIRE 16 -1 (-3050 2775)(-3050 2625);
WIRE 16 -1 (-3500 2775)(-3050 2775);
WIRE 16 -1 (-3500 3450)(-3500 2775);
WIRE 16 -1 (-3500 2775)(-3675 2775);
WIRE 16 -1 (-3500 4075)(-3500 3450);
WIRE 16 -1 (-3500 3450)(-3325 3450);
WIRE 16 -1 (-3325 3450)(-3100 3450);
WIRE 16 -1 (-3325 3450)(-3325 3325);
WIRE 16 -1 (-3500 4725)(-3500 4075);
WIRE 16 -1 (-3500 4075)(-3325 4075);
WIRE 16 -1 (-3325 4075)(-3100 4075);
WIRE 16 -1 (-3325 3950)(-3325 4075);
WIRE 16 -1 (-3500 4725)(-3325 4725);
WIRE 16 -1 (-3575 4725)(-3500 4725);
WIRE 16 -1 (-3100 3450)(-2850 3450);
WIRE 16 -1 (-3100 3450)(-3100 3325);
WIRE 16 -1 (-2850 3450)(-2625 3450);
WIRE 16 -1 (-2850 3450)(-2850 3325);
WIRE 16 -1 (-3325 5075)(-3325 4725);
WIRE 16 -1 (-3325 4725)(-3100 4725);
WIRE 16 -1 (-3325 4725)(-3325 4575);
WIRE 16 -1 (-3100 4075)(-2875 4075);
WIRE 16 -1 (-3100 3950)(-3100 4075);
WIRE 16 -1 (-2875 4075)(-2650 4075);
WIRE 16 -1 (-2875 3950)(-2875 4075);
WIRE 16 -1 (-2875 4725)(-3100 4725);
WIRE 16 -1 (-3100 4725)(-3100 4575);
WIRE 16 -1 (-2625 3450)(-2375 3450);
WIRE 16 -1 (-2625 3450)(-2625 3325);
WIRE 16 -1 (-2100 3450)(-2375 3450);
WIRE 16 -1 (-2375 3450)(-2375 3300);
WIRE 16 -1 (-2650 4725)(-2875 4725);
WIRE 16 -1 (-2875 4725)(-2875 4575);
WIRE 16 -1 (-2650 4075)(-2400 4075);
WIRE 16 -1 (-2650 3950)(-2650 4075);
WIRE 16 -1 (-2400 4075)(-2175 4075);
WIRE 16 -1 (-2400 3950)(-2400 4075);
WIRE 16 -1 (-2400 4725)(-2650 4725);
WIRE 16 -1 (-2650 4725)(-2650 4575);
WIRE 16 -1 (-1825 3450)(-2100 3450);
WIRE 16 -1 (-2100 3300)(-2100 3450);
WIRE 16 -1 (-1575 3450)(-1825 3450);
WIRE 16 -1 (-1825 3300)(-1825 3450);
WIRE 16 -1 (-2175 4725)(-2400 4725);
WIRE 16 -1 (-2400 4725)(-2400 4575);
WIRE 16 -1 (-2175 4075)(-1950 4075);
WIRE 16 -1 (-2175 3950)(-2175 4075);
WIRE 16 -1 (-1950 4075)(-1725 4075);
WIRE 16 -1 (-1950 3950)(-1950 4075);
WIRE 16 -1 (-1950 4725)(-2175 4725);
WIRE 16 -1 (-2175 4725)(-2175 4575);
WIRE 16 -1 (-1575 3450)(-1325 3450);
WIRE 16 -1 (-1575 3450)(-1575 3300);
WIRE 16 -1 (-1325 3450)(-1325 3300);
WIRE 16 -1 (-1725 4725)(-1950 4725);
WIRE 16 -1 (-1950 4725)(-1950 4575);
WIRE 16 -1 (-1725 4075)(-1500 4075);
WIRE 16 -1 (-1725 3950)(-1725 4075);
WIRE 16 -1 (-1250 4075)(-1500 4075);
WIRE 16 -1 (-1500 3950)(-1500 4075);
WIRE 16 -1 (-1425 4725)(-1725 4725);
WIRE 16 -1 (-1725 4725)(-1725 4575);
WIRE 16 -1 (-1425 4725)(-1125 4725);
WIRE 16 -1 (-1425 4725)(-1425 4575);
WIRE 16 -1 (-1250 4075)(-1250 3950);
WIRE 16 -1 (-1125 4725)(-1125 4575);
WIRE 16 -1 (-3325 3750)(-3325 3625);
WIRE 16 -1 (-3325 3625)(-3100 3625);
WIRE 16 -1 (-3100 3625)(-2875 3625);
WIRE 16 -1 (-3100 3750)(-3100 3625);
WIRE 16 -1 (-2875 3625)(-2650 3625);
WIRE 16 -1 (-2875 3750)(-2875 3625);
WIRE 16 -1 (-2650 3625)(-2400 3625);
WIRE 16 -1 (-2650 3750)(-2650 3625);
WIRE 16 -1 (-2400 3625)(-2175 3625);
WIRE 16 -1 (-2400 3750)(-2400 3625);
WIRE 16 -1 (-2175 3625)(-1950 3625);
WIRE 16 -1 (-2175 3750)(-2175 3625);
WIRE 16 -1 (-1950 3625)(-1725 3625);
WIRE 16 -1 (-1950 3750)(-1950 3625);
WIRE 16 -1 (-1725 3625)(-1500 3625);
WIRE 16 -1 (-1725 3750)(-1725 3625);
WIRE 16 -1 (-1250 3625)(-1500 3625);
WIRE 16 -1 (-1500 3750)(-1500 3625);
WIRE 16 -1 (-725 3625)(-1250 3625);
WIRE 16 -1 (-1250 3750)(-1250 3625);
WIRE 16 -1 (-725 4225)(-725 3625);
WIRE 16 -1 (-725 3625)(-725 2900);
WIRE 16 -1 (-725 2900)(-1325 2900);
WIRE 16 -1 (-725 2900)(-725 2850);
WIRE 16 -1 (-725 4225)(-1125 4225);
WIRE 16 -1 (-1125 4375)(-1125 4225);
WIRE 16 -1 (-1125 4225)(-1425 4225);
WIRE 16 -1 (-1325 3100)(-1325 2900);
WIRE 16 -1 (-1325 2900)(-1575 2900);
WIRE 16 -1 (-1575 3100)(-1575 2900);
WIRE 16 -1 (-1575 2900)(-1825 2900);
WIRE 16 -1 (-1425 4375)(-1425 4225);
WIRE 16 -1 (-1425 4225)(-1725 4225);
WIRE 16 -1 (-1725 4375)(-1725 4225);
WIRE 16 -1 (-1725 4225)(-1950 4225);
WIRE 16 -1 (-1825 3100)(-1825 2900);
WIRE 16 -1 (-1825 2900)(-2100 2900);
WIRE 16 -1 (-2100 3100)(-2100 2900);
WIRE 16 -1 (-2100 2900)(-2375 2900);
WIRE 16 -1 (-1950 4375)(-1950 4225);
WIRE 16 -1 (-1950 4225)(-2175 4225);
WIRE 16 -1 (-2175 4375)(-2175 4225);
WIRE 16 -1 (-2175 4225)(-2400 4225);
WIRE 16 -1 (-2375 3100)(-2375 2900);
WIRE 16 -1 (-2375 2900)(-2625 2900);
WIRE 16 -1 (-2625 3125)(-2625 2900);
WIRE 16 -1 (-2850 2900)(-2625 2900);
WIRE 16 -1 (-2400 4375)(-2400 4225);
WIRE 16 -1 (-2400 4225)(-2650 4225);
WIRE 16 -1 (-2650 4375)(-2650 4225);
WIRE 16 -1 (-2875 4225)(-2650 4225);
WIRE 16 -1 (-2850 3125)(-2850 2900);
WIRE 16 -1 (-3100 2900)(-2850 2900);
WIRE 16 -1 (-3100 3125)(-3100 2900);
WIRE 16 -1 (-3325 2900)(-3100 2900);
WIRE 16 -1 (-2875 4375)(-2875 4225);
WIRE 16 -1 (-3100 4225)(-2875 4225);
WIRE 16 -1 (-3100 4375)(-3100 4225);
WIRE 16 -1 (-3325 4225)(-3100 4225);
WIRE 16 -1 (-3325 3125)(-3325 2900);
WIRE 16 -1 (-3325 4375)(-3325 4225);
WIRE 16 -1 (-8000 4725)(-8000 4575);
WIRE 16 -1 (-8000 5450)(-8000 4725);
WIRE 16 -1 (-8000 4725)(-7725 4725);
WIRE 16 -1 (-8000 4575)(-7950 4575);
WIRE 16 -1 (-8000 4575)(-8050 4575);
WIRE 16 -1 (-8050 4575)(-8050 4500);
WIRE 16 -1 (-7950 4575)(-7950 4475);
WIRE 16 -1 (-6900 5450)(-8000 5450);
WIRE 16 -1 (-8000 5525)(-8000 5450);
WIRE 16 -1 (-6900 5450)(-6650 5450);
WIRE 16 -1 (-6900 5450)(-6900 5400);
WIRE 16 -1 (-6650 5450)(-6400 5450);
WIRE 16 -1 (-6650 5450)(-6650 5400);
WIRE 16 -1 (-6400 5450)(-6400 5375);
WIRE 16 -1 (-6400 5450)(-6150 5450);
WIRE 16 -1 (-6150 5450)(-6150 5375);
WIRE 16 -1 (-6150 5175)(-6150 5050);
WIRE 16 -1 (-6225 5050)(-6150 5050);
WIRE 16 -1 (-6400 5050)(-6225 5050);
WIRE 16 -1 (-6400 5175)(-6400 5050);
WIRE 16 -1 (-6650 5050)(-6400 5050);
WIRE 16 -1 (-6650 5200)(-6650 5050);
WIRE 16 -1 (-6900 5050)(-6650 5050);
WIRE 16 -1 (-6900 5200)(-6900 5050);
WIRE 16 -1 (-5000 4725)(-5000 4575);
WIRE 16 -1 (-5000 4725)(-5275 4725);
WIRE 16 -1 (-5275 4725)(-5525 4725);
WIRE 16 -1 (-5275 4725)(-5275 4575);
WIRE 16 -1 (-5525 4725)(-5525 4575);
WIRE 16 -1 (-5525 4725)(-5775 4725);
WIRE 16 -1 (-6000 4725)(-5775 4725);
WIRE 16 -1 (-5775 4725)(-5775 4575);
WIRE 16 -1 (-6000 4725)(-6000 4575);
WIRE 16 -1 (-6000 4725)(-6200 4725);
WIRE 16 -1 (-6200 4725)(-6425 4725);
WIRE 16 -1 (-6200 4725)(-6200 4575);
WIRE 16 -1 (-6625 4725)(-6425 4725);
WIRE 16 -1 (-6425 4725)(-6425 4575);
WIRE 16 -1 (-6625 4725)(-6625 4575);
WIRE 16 -1 (-6625 4725)(-6825 4725);
WIRE 16 -1 (-7050 4725)(-6825 4725);
WIRE 16 -1 (-6825 4725)(-6825 4575);
WIRE 16 -1 (-7050 4725)(-7150 4725);
WIRE 16 -1 (-7050 4725)(-7050 4575);
WIRE 16 -1 (-7150 4900)(-7150 4725);
WIRE 16 -1 (-7150 4725)(-7525 4725);
WIRE 16 -1 (-7150 3950)(-7150 4725);
WIRE 16 -1 (-7250 3950)(-7150 3950);
WIRE 16 -1 (-7250 3950)(-7250 3850);
WIRE 16 -1 (-7250 4050)(-7250 3950);
WIRE 16 -1 (-7450 4050)(-7250 4050);
WIRE 16 -1 (-7450 3850)(-7250 3850);
WIRE 16 -1 (-5000 4375)(-5000 4275);
WIRE 16 -1 (-5275 4275)(-5000 4275);
WIRE 16 -1 (-5275 4375)(-5275 4275);
WIRE 16 -1 (-5525 4275)(-5275 4275);
WIRE 16 -1 (-5525 4375)(-5525 4275);
WIRE 16 -1 (-5775 4275)(-5525 4275);
WIRE 16 -1 (-5775 4375)(-5775 4275);
WIRE 16 -1 (-6000 4275)(-5775 4275);
WIRE 16 -1 (-6200 4275)(-6000 4275);
WIRE 16 -1 (-6000 4375)(-6000 4275);
WIRE 16 -1 (-6000 4275)(-6000 4200);
WIRE 16 -1 (-6200 4375)(-6200 4275);
WIRE 16 -1 (-6425 4275)(-6200 4275);
WIRE 16 -1 (-6425 4375)(-6425 4275);
WIRE 16 -1 (-6625 4275)(-6425 4275);
WIRE 16 -1 (-6625 4375)(-6625 4275);
WIRE 16 -1 (-6825 4275)(-6625 4275);
WIRE 16 -1 (-6825 4375)(-6825 4275);
WIRE 16 -1 (-7050 4275)(-6825 4275);
WIRE 16 -1 (-7050 4375)(-7050 4275);
WIRE 16 -1 (-975 5975)(-975 5800);
WIRE 16 -1 (-1250 5975)(-975 5975);
WIRE 16 -1 (-1250 5975)(-1250 5800);
WIRE 16 -1 (-1500 5975)(-1250 5975);
WIRE 16 -1 (-1500 5800)(-1500 5975);
WIRE 16 -1 (-1775 5975)(-1500 5975);
WIRE 16 -1 (-1775 5975)(-1775 5800);
WIRE 16 -1 (-2075 5975)(-1775 5975);
WIRE 16 -1 (-2075 5975)(-2075 5825);
WIRE 16 -1 (-2375 5975)(-2075 5975);
WIRE 16 -1 (-2375 5975)(-2375 5825);
WIRE 16 -1 (-2675 5975)(-2375 5975);
WIRE 16 -1 (-2675 5975)(-2675 5825);
WIRE 16 -1 (-3000 5975)(-2675 5975);
WIRE 16 -1 (-3000 5975)(-3000 5850);
WIRE 16 -1 (-3275 5975)(-3000 5975);
WIRE 16 -1 (-3275 5975)(-3275 5850);
WIRE 16 -1 (-4150 5975)(-3275 5975);
WIRE 16 -1 (-4150 6200)(-4150 5975);
WIRE 16 -1 (-4150 4725)(-4150 5975);
WIRE 16 -1 (-3775 4725)(-4150 4725);
WIRE 16 -1 (-4150 4725)(-4150 3150);
WIRE 16 -1 (-975 5600)(-975 5425);
WIRE 16 -1 (-975 5425)(-1050 5425);
WIRE 16 -1 (-1050 5425)(-1250 5425);
WIRE 16 -1 (-1050 5425)(-1050 5350);
WIRE 16 -1 (-1250 5600)(-1250 5425);
WIRE 16 -1 (-1500 5425)(-1250 5425);
WIRE 16 -1 (-1500 5600)(-1500 5425);
WIRE 16 -1 (-1775 5425)(-1500 5425);
WIRE 16 -1 (-1775 5600)(-1775 5425);
WIRE 16 -1 (-1775 5425)(-2075 5425);
WIRE 16 -1 (-2075 5625)(-2075 5425);
WIRE 16 -1 (-2375 5425)(-2075 5425);
WIRE 16 -1 (-2375 5625)(-2375 5425);
WIRE 16 -1 (-2675 5425)(-2375 5425);
WIRE 16 -1 (-2675 5625)(-2675 5425);
WIRE 16 -1 (-3000 5425)(-2675 5425);
WIRE 16 -1 (-3000 5650)(-3000 5425);
WIRE 16 -1 (-3275 5425)(-3000 5425);
WIRE 16 -1 (-3275 5650)(-3275 5425);
WIRE 16 -1 (-3050 2425)(-3050 2300);
WIRE 16 -1 (-3050 2300)(-2750 2300);
WIRE 16 -1 (-2750 2300)(-2525 2300);
WIRE 16 -1 (-2750 2425)(-2750 2300);
WIRE 16 -1 (-2525 2300)(-2275 2300);
WIRE 16 -1 (-2525 2425)(-2525 2300);
WIRE 16 -1 (-2275 2300)(-2025 2300);
WIRE 16 -1 (-2275 2425)(-2275 2300);
WIRE 16 -1 (-2025 2300)(-1750 2300);
WIRE 16 -1 (-2025 2425)(-2025 2300);
WIRE 16 -1 (-1475 2300)(-1750 2300);
WIRE 16 -1 (-1750 2425)(-1750 2300);
WIRE 16 -1 (-1475 2300)(-1225 2300);
WIRE 16 -1 (-1475 2425)(-1475 2300);
WIRE 16 -1 (-975 2300)(-1225 2300);
WIRE 16 -1 (-1225 2425)(-1225 2300);
WIRE 16 -1 (-1225 2300)(-1225 2150);
WIRE 16 -1 (-675 2300)(-975 2300);
WIRE 16 -1 (-975 2425)(-975 2300);
WIRE 16 -1 (-375 2300)(-675 2300);
WIRE 16 -1 (-675 2425)(-675 2300);
WIRE 16 -1 (-375 2425)(-375 2300);
WIRE 16 -1 (-7650 4050)(-7900 4050);
WIRE 16 -1 (-7900 4050)(-7900 3950);
WIRE 16 -1 (-7900 3950)(-7900 3850);
WIRE 16 -1 (-8000 3950)(-7900 3950);
WIRE 16 -1 (-8000 3950)(-8000 4125);
WIRE 16 -1 (-8000 3625)(-8000 3950);
WIRE 16 -1 (-7900 3850)(-7650 3850);
WIRE 16 -1 (-8000 3625)(-6750 3625);
WIRE 16 -1 (-8000 4125)(-7950 4125);
WIRE 16 -1 (-8050 4125)(-8000 4125);
WIRE 16 -1 (-8050 4125)(-8050 4300);
WIRE 16 -1 (-7950 4125)(-7950 4275);
WIRE 16 -1 (-6625 3625)(-6750 3625);
WIRE 16 -1 (-6750 3625)(-6750 3725);
WIRE 16 -1 (-6625 3625)(-6350 3625);
WIRE 16 -1 (-6625 3500)(-6625 3625);
WIRE 16 -1 (-6350 3625)(-6350 3475);
WIRE 16 -1 (-2075 1525)(-2075 1675);
WIRE 16 -1 (-2075 1675)(-2325 1675);
WIRE 16 -1 (-2325 1525)(-2325 1675);
WIRE 16 -1 (-2325 1675)(-2625 1675);
WIRE 16 -1 (-2625 1675)(-2875 1675);
WIRE 16 -1 (-2625 1675)(-2625 1525);
WIRE 16 -1 (-2875 1675)(-3000 1675);
WIRE 16 -1 (-2875 1675)(-2875 1525);
WIRE 16 -1 (-3000 1900)(-3000 1675);
WIRE 16 -1 (-4150 1675)(-3000 1675);
WIRE 16 -1 (-4150 1675)(-4150 2775);
WIRE 16 -1 (-4150 2775)(-3875 2775);
WIRE 16 -1 (-4150 2950)(-4150 2775);
WIRE 16 -1 (-2075 1325)(-2075 1200);
WIRE 16 -1 (-2075 1200)(-2175 1200);
WIRE 16 -1 (-2325 1200)(-2175 1200);
WIRE 16 -1 (-2175 1200)(-2175 1150);
WIRE 16 -1 (-2325 1325)(-2325 1200);
WIRE 16 -1 (-2625 1200)(-2325 1200);
WIRE 16 -1 (-2625 1325)(-2625 1200);
WIRE 16 -1 (-2875 1200)(-2625 1200);
WIRE 16 -1 (-2875 1325)(-2875 1200);
WIRE 16 -1 (-6625 3300)(-6625 3125);
WIRE 16 -1 (-6625 3125)(-6350 3125);
WIRE 16 -1 (-6350 3275)(-6350 3125);
WIRE 16 -1 (-6350 3125)(-6350 3025);
DOT 1 (-975 2300);
DOT 1 (-975 2775);
DOT 1 (-675 2300);
DOT 1 (-675 2775);
DOT 1 (-1225 2300);
DOT 1 (-1225 2775);
DOT 1 (-1575 2900);
DOT 1 (-1325 2900);
DOT 1 (-2175 4075);
DOT 1 (-2400 4225);
DOT 1 (-3100 4225);
DOT 1 (-1825 2900);
DOT 1 (-8000 4575);
DOT 1 (-7150 4725);
DOT 1 (-3100 2900);
DOT 1 (-1250 5975);
DOT 1 (-1050 5425);
DOT 1 (-1250 5425);
DOT 1 (-1500 5425);
DOT 1 (-1425 4725);
DOT 1 (-2075 5975);
DOT 1 (-2375 5975);
DOT 1 (-1775 5425);
DOT 1 (-1725 4725);
DOT 1 (-2675 5425);
DOT 1 (-3000 5975);
DOT 1 (-3275 5975);
DOT 1 (-3000 5425);
DOT 1 (-3500 4725);
DOT 1 (-1500 3625);
DOT 1 (-2025 2775);
DOT 1 (-2400 3625);
DOT 1 (-3050 2775);
DOT 1 (-3500 3450);
DOT 1 (-3500 2775);
DOT 1 (-1750 2300);
DOT 1 (-2625 1675);
DOT 1 (-2750 2300);
DOT 1 (-3000 1675);
DOT 1 (-4150 5975);
DOT 1 (-4150 4725);
DOT 1 (-5275 4725);
DOT 1 (-5525 4725);
DOT 1 (-6200 4725);
DOT 1 (-6400 5450);
DOT 1 (-6650 5450);
DOT 1 (-6400 5050);
DOT 1 (-6425 4725);
DOT 1 (-6650 5050);
DOT 1 (-6825 4725);
DOT 1 (-4150 2775);
DOT 1 (-5275 4275);
DOT 1 (-5525 4275);
DOT 1 (-6425 4275);
DOT 1 (-6625 4275);
DOT 1 (-6825 4275);
DOT 1 (-6625 3625);
DOT 1 (-6750 3625);
DOT 1 (-6350 3125);
DOT 1 (-7250 3950);
DOT 1 (-8000 4725);
DOT 1 (-7900 3950);
DOT 1 (-8000 3950);
DOT 1 (-8000 4125);
DOT 1 (-8000 5450);
DOT 1 (-2625 2900);
DOT 1 (-3325 4725);
DOT 1 (-2675 5975);
DOT 1 (-1500 5975);
DOT 1 (-1775 5975);
DOT 1 (-6900 5450);
DOT 1 (-6625 4725);
DOT 1 (-6000 4275);
DOT 1 (-7050 4725);
DOT 1 (-5775 4725);
DOT 1 (-6000 4725);
DOT 1 (-5775 4275);
DOT 1 (-6200 4275);
DOT 1 (-2375 5425);
DOT 1 (-1950 4725);
DOT 1 (-2875 4725);
DOT 1 (-2400 4725);
DOT 1 (-3325 4075);
DOT 1 (-2175 4725);
DOT 1 (-2650 4725);
DOT 1 (-2875 4075);
DOT 1 (-2175 3625);
DOT 1 (-1725 4075);
DOT 1 (-2400 4075);
DOT 1 (-1950 4075);
DOT 1 (-1725 4225);
DOT 1 (-2175 4225);
DOT 1 (-2650 4225);
DOT 1 (-1125 4225);
DOT 1 (-1500 4075);
DOT 1 (-1425 4225);
DOT 1 (-1950 4225);
DOT 1 (-2275 2775);
DOT 1 (-3325 3450);
DOT 1 (-2875 4225);
DOT 1 (-3500 4075);
DOT 1 (-2025 2300);
DOT 1 (-3100 3450);
DOT 1 (-2750 2775);
DOT 1 (-1725 3625);
DOT 1 (-2625 3450);
DOT 1 (-1250 3625);
DOT 1 (-2650 4075);
DOT 1 (-1950 3625);
DOT 1 (-1475 2775);
DOT 1 (-3100 4075);
DOT 1 (-2525 2300);
DOT 1 (-2525 2775);
DOT 1 (-2850 3450);
DOT 1 (-725 3625);
DOT 1 (-2875 3625);
DOT 1 (-3100 3625);
DOT 1 (-2850 2900);
DOT 1 (-2275 2300);
DOT 1 (-2175 1200);
DOT 1 (-3100 4725);
DOT 1 (-2075 5425);
DOT 1 (-2625 1200);
DOT 1 (-2875 1675);
DOT 1 (-2325 1675);
DOT 1 (-2325 1200);
DOT 1 (-725 2900);
DOT 1 (-2375 3450);
DOT 1 (-2375 2900);
DOT 1 (-2100 2900);
DOT 1 (-1825 3450);
DOT 1 (-1575 3450);
DOT 1 (-2650 3625);
DOT 1 (-1475 2300);
DOT 1 (-2100 3450);
DOT 1 (-1750 2775);
QUIT
